FILE_TYPE = MACRO_DRAWING;
SET COLOR_WIRE YELLOW;
SET COLOR_PROP ORANGE;
SET COLOR_DOT WHITE;
SET COLOR_ARC YELLOW;
SET COLOR_BODY GREEN;
SET COLOR_NOTE PURPLE;
SET PROP_DISPLAY VALUE;
SET PAGE_NUMBER P249;
FORCEADD OFFPAGE..1
(-8700 2550);
FORCEPROP 2 LAST $XR1 151 
J 0
(-9102 2550);
DISPLAY 0.638298 (-9102 2550);
PAINT MONO (-9102 2550);
FORCEPROP 2 LAST $XR0 150 
J 0
(-8982 2550);
DISPLAY 0.638298 (-8982 2550);
PAINT MONO (-8982 2550);
FORCEPROP 2 LAST CDS_LIB standard
J 0
(-8700 2550);
PAINT MONO (-8700 2550);
DISPLAY INVISIBLE (-8700 2550);
FORCEPROP 1 LAST OFFPAGE TRUE
J 0
(-8375 2425);
DISPLAY 0.872340 (-8375 2425);
DISPLAY INVISIBLE (-8375 2425);
FORCEPROP 1 LAST COMMENT_BODY TRUE
J 0
(-8575 2450);
DISPLAY 0.872340 (-8575 2450);
PAINT GREEN (-8575 2450);
DISPLAY INVISIBLE (-8575 2450);
FORCEPROP 2 LAST PATH I1
J 0
(-8650 2625);
DISPLAY 0.680851 (-8650 2625);
DISPLAY INVISIBLE (-8650 2625);
FORCEADD OFFPAGE..1
(-6600 1225);
FORCEPROP 2 LAST $XR1 151 
J 0
(-6972 1225);
DISPLAY 0.638298 (-6972 1225);
PAINT MONO (-6972 1225);
FORCEPROP 2 LAST $XR0 150 
J 0
(-6852 1225);
DISPLAY 0.638298 (-6852 1225);
PAINT MONO (-6852 1225);
FORCEPROP 2 LAST CDS_LIB standard
J 0
(-6600 1225);
PAINT MONO (-6600 1225);
DISPLAY INVISIBLE (-6600 1225);
FORCEPROP 1 LAST OFFPAGE TRUE
J 0
(-6275 1100);
DISPLAY 0.872340 (-6275 1100);
DISPLAY INVISIBLE (-6275 1100);
FORCEPROP 1 LAST COMMENT_BODY TRUE
J 0
(-6475 1125);
DISPLAY 0.872340 (-6475 1125);
PAINT GREEN (-6475 1125);
DISPLAY INVISIBLE (-6475 1125);
FORCEPROP 2 LAST PATH I10
J 0
(-6550 1300);
DISPLAY 0.680851 (-6550 1300);
DISPLAY INVISIBLE (-6550 1300);
FORCEADD OFFPAGE..4
R 2
(-6600 1325);
FORCEPROP 2 LAST $XR1 249 
J 0
(-6941 1325);
DISPLAY 0.638298 (-6941 1325);
PAINT MONO (-6941 1325);
FORCEPROP 2 LAST $XR0 80 
J 0
(-6821 1325);
DISPLAY 0.638298 (-6821 1325);
PAINT MONO (-6821 1325);
FORCEPROP 2 LAST CDS_LIB standard
J 2
(-6600 1325);
DISPLAY INVISIBLE (-6600 1325);
FORCEPROP 1 LAST OFFPAGE TRUE
J 2
(-6925 1200);
DISPLAY 0.872340 (-6925 1200);
DISPLAY INVISIBLE (-6925 1200);
FORCEPROP 1 LAST COMMENT_BODY TRUE
J 2
(-6575 1225);
DISPLAY 0.872340 (-6575 1225);
PAINT GREEN (-6575 1225);
DISPLAY INVISIBLE (-6575 1225);
FORCEPROP 2 LAST PATH I11
J 0
(-6875 1375);
DISPLAY 0.680851 (-6875 1375);
DISPLAY INVISIBLE (-6875 1375);
FORCEADD Q_RES..1
(-7825 2750);
FORCEPROP 1 LAST LOCATION R2992
J 0
(-8025 2750);
DISPLAY 0.638298 (-8025 2750);
FORCEPROP 0 LAST $SEC 1
J 0
(-7700 2850);
DISPLAY 0.680851 (-7700 2850);
PAINT MONO (-7700 2850);
DISPLAY INVISIBLE (-7700 2850);
FORCEPROP 0 LAST CDS_SEC 1
J 0
(-7700 2850);
DISPLAY 1.021277 (-7700 2850);
DISPLAY INVISIBLE (-7700 2850);
FORCEPROP 1 LASTPIN (-7925 2750) $PN 1
J 0
(-7913 2762);
DISPLAY 0.787234 (-7913 2762);
PAINT MONO (-7913 2762);
FORCEPROP 1 LASTPIN (-7725 2750) $PN 2
J 0
(-7763 2762);
DISPLAY 0.787234 (-7763 2762);
PAINT MONO (-7763 2762);
FORCEPROP 1 LAST VALUE 0
J 2
(-7650 2750);
DISPLAY 0.510638 (-7650 2750);
FORCEPROP 1 LAST TOLERANCE 5%
J 0
(-7600 2750);
DISPLAY 0.510638 (-7600 2750);
FORCEPROP 1 LAST MATERIAL CHIP
J 0
(-7550 2750);
DISPLAY 0.510638 (-7550 2750);
FORCEPROP 1 LAST WATTAGE 1/16W
J 2
(-7725 2700);
DISPLAY 0.404255 (-7725 2700);
DISPLAY INVISIBLE (-7725 2700);
FORCEPROP 1 LAST PACK_TYPE 0402LF
J 0
(-7925 2700);
DISPLAY 0.404255 (-7925 2700);
DISPLAY INVISIBLE (-7925 2700);
FORCEPROP 2 LAST CDS_LIB pure_quanta
J 0
(-7825 2750);
DISPLAY INVISIBLE (-7825 2750);
FORCEPROP 1 LAST PATH I12
J 0
(-7875 2900);
DISPLAY 0.978723 (-7875 2900);
PAINT WHITE (-7875 2900);
DISPLAY INVISIBLE (-7875 2900);
FORCEPROP 1 LAST PART_NUMBER CS00002JB13
J 0
(-7925 2675);
DISPLAY 0.404255 (-7925 2675);
DISPLAY INVISIBLE (-7925 2675);
FORCEADD Q_RES..1
(-7825 2650);
FORCEPROP 1 LAST LOCATION R3107
J 0
(-7975 2625);
DISPLAY 0.510638 (-7975 2625);
FORCEPROP 0 LAST $SEC 1
J 0
(-7900 2700);
DISPLAY 0.680851 (-7900 2700);
PAINT MONO (-7900 2700);
DISPLAY INVISIBLE (-7900 2700);
FORCEPROP 0 LAST CDS_SEC 1
J 0
(-7900 2700);
DISPLAY 1.021277 (-7900 2700);
DISPLAY INVISIBLE (-7900 2700);
FORCEPROP 1 LASTPIN (-7925 2650) $PN 1
J 0
(-7913 2662);
DISPLAY 0.787234 (-7913 2662);
PAINT MONO (-7913 2662);
FORCEPROP 1 LASTPIN (-7725 2650) $PN 2
J 0
(-7763 2662);
DISPLAY 0.787234 (-7763 2662);
PAINT MONO (-7763 2662);
FORCEPROP 1 LAST TOLERANCE 5%
J 0
(-7625 2650);
DISPLAY 0.510638 (-7625 2650);
FORCEPROP 1 LAST MATERIAL CHIP
J 0
(-7575 2650);
DISPLAY 0.510638 (-7575 2650);
FORCEPROP 1 LAST VALUE 0
J 2
(-7675 2650);
DISPLAY 0.510638 (-7675 2650);
FORCEPROP 1 LAST PACK_TYPE 0402LF
J 0
(-7975 2600);
DISPLAY 0.404255 (-7975 2600);
DISPLAY INVISIBLE (-7975 2600);
FORCEPROP 1 LAST WATTAGE 1/16W
J 2
(-7675 2600);
DISPLAY 0.404255 (-7675 2600);
DISPLAY INVISIBLE (-7675 2600);
FORCEPROP 2 LAST CDS_LIB pure_quanta
J 0
(-7825 2650);
DISPLAY INVISIBLE (-7825 2650);
FORCEPROP 1 LAST PATH I13
J 0
(-7875 2800);
DISPLAY 0.978723 (-7875 2800);
PAINT WHITE (-7875 2800);
DISPLAY INVISIBLE (-7875 2800);
FORCEPROP 1 LAST PART_NUMBER CS00002JB13
J 0
(-7850 2575);
DISPLAY 0.404255 (-7850 2575);
DISPLAY INVISIBLE (-7850 2575);
FORCEADD Q_RES..1
(-7825 2550);
FORCEPROP 1 LAST LOCATION R3108
J 0
(-7975 2525);
DISPLAY 0.510638 (-7975 2525);
FORCEPROP 0 LAST $SEC 1
J 0
(-7900 2600);
DISPLAY 0.680851 (-7900 2600);
PAINT MONO (-7900 2600);
DISPLAY INVISIBLE (-7900 2600);
FORCEPROP 0 LAST CDS_SEC 1
J 0
(-7900 2600);
DISPLAY 1.021277 (-7900 2600);
DISPLAY INVISIBLE (-7900 2600);
FORCEPROP 1 LASTPIN (-7925 2550) $PN 1
J 0
(-7913 2562);
DISPLAY 0.787234 (-7913 2562);
PAINT MONO (-7913 2562);
FORCEPROP 1 LASTPIN (-7725 2550) $PN 2
J 0
(-7763 2562);
DISPLAY 0.787234 (-7763 2562);
PAINT MONO (-7763 2562);
FORCEPROP 1 LAST VALUE 0
J 2
(-7675 2550);
DISPLAY 0.510638 (-7675 2550);
FORCEPROP 1 LAST TOLERANCE 5%
J 0
(-7625 2550);
DISPLAY 0.510638 (-7625 2550);
FORCEPROP 1 LAST MATERIAL CHIP
J 0
(-7575 2550);
DISPLAY 0.510638 (-7575 2550);
FORCEPROP 1 LAST PACK_TYPE 0402LF
J 0
(-7900 2500);
DISPLAY 0.404255 (-7900 2500);
FORCEPROP 1 LAST WATTAGE 1/16W
J 2
(-7675 2500);
DISPLAY 0.404255 (-7675 2500);
FORCEPROP 2 LAST CDS_LIB pure_quanta
J 0
(-7825 2550);
DISPLAY INVISIBLE (-7825 2550);
FORCEPROP 1 LAST PATH I14
J 0
(-7875 2700);
DISPLAY 0.978723 (-7875 2700);
PAINT WHITE (-7875 2700);
DISPLAY INVISIBLE (-7875 2700);
FORCEPROP 1 LAST PART_NUMBER CS00002JB13
J 0
(-7900 2450);
DISPLAY 0.404255 (-7900 2450);
DISPLAY INVISIBLE (-7900 2450);
FORCEADD LTC4307CMS8..1
(-6500 2600);
FORCEPROP 1 LAST LOCATION U200
J 0
(-6750 2905);
DISPLAY 0.723404 (-6750 2905);
PAINT GREEN (-6750 2905);
FORCEPROP 0 LAST $SEC 1
J 0
(-6750 3050);
DISPLAY 0.680851 (-6750 3050);
PAINT MONO (-6750 3050);
DISPLAY INVISIBLE (-6750 3050);
FORCEPROP 0 LAST CDS_SEC 1
J 0
(-6750 3050);
DISPLAY 1.021277 (-6750 3050);
DISPLAY INVISIBLE (-6750 3050);
FORCEPROP 0 LASTPIN (-6900 2750) $PN 1
J 2
(-6910 2760);
DISPLAY 0.680851 (-6910 2760);
PAINT MONO (-6910 2760);
FORCEPROP 0 LASTPIN (-6900 2450) $PN 4
J 2
(-6910 2460);
DISPLAY 0.680851 (-6910 2460);
PAINT MONO (-6910 2460);
FORCEPROP 0 LASTPIN (-6100 2450) $PN 5
J 0
(-6090 2460);
DISPLAY 0.680851 (-6090 2460);
PAINT MONO (-6090 2460);
FORCEPROP 0 LASTPIN (-6900 2650) $PN 3
J 2
(-6910 2660);
DISPLAY 0.680851 (-6910 2660);
PAINT MONO (-6910 2660);
FORCEPROP 0 LASTPIN (-6100 2650) $PN 2
J 0
(-6090 2660);
DISPLAY 0.680851 (-6090 2660);
PAINT MONO (-6090 2660);
FORCEPROP 0 LASTPIN (-6900 2550) $PN 6
J 2
(-6910 2560);
DISPLAY 0.680851 (-6910 2560);
PAINT MONO (-6910 2560);
FORCEPROP 0 LASTPIN (-6100 2550) $PN 7
J 0
(-6090 2560);
DISPLAY 0.680851 (-6090 2560);
PAINT MONO (-6090 2560);
FORCEPROP 0 LASTPIN (-6100 2750) $PN 8
J 0
(-6090 2760);
DISPLAY 0.680851 (-6090 2760);
PAINT MONO (-6090 2760);
FORCEPROP 1 LAST MATERIAL IC
J 0
(-6750 2810);
DISPLAY 0.723404 (-6750 2810);
PAINT GREEN (-6750 2810);
FORCEPROP 2 LAST PART_TYPE SMLF
J 0
(-6750 3000);
DISPLAY 1.021277 (-6750 3000);
FORCEPROP 2 LAST VALUE LTC4307CMS8
J 0
(-6750 2950);
DISPLAY 1.021277 (-6750 2950);
FORCEPROP 2 LAST CDS_LIB pure_quanta
J 0
(-6500 2600);
DISPLAY INVISIBLE (-6500 2600);
FORCEPROP 1 LAST NEEDS_NO_SIZE TRUE
J 0
(-6500 2600);
DISPLAY 0.468085 (-6500 2600);
PAINT GREEN (-6500 2600);
DISPLAY INVISIBLE (-6500 2600);
FORCEPROP 1 LAST PATH I15
J 0
(-6275 2805);
DISPLAY 0.723404 (-6275 2805);
PAINT GREEN (-6275 2805);
DISPLAY INVISIBLE (-6275 2805);
FORCEPROP 1 LAST PART_NUMBER AL004307000
J 0
(-6750 2860);
DISPLAY 0.723404 (-6750 2860);
PAINT GREEN (-6750 2860);
DISPLAY INVISIBLE (-6750 2860);
FORCEADD UNIVERSAL_GND..1
(-6900 2325);
FORCEPROP 3 LASTPIN (-6900 2375) SIG_NAME GND\g
J 0
(-6890 2385);
DISPLAY 0.659574 (-6890 2385);
PAINT MONO (-6890 2385);
DISPLAY INVISIBLE (-6890 2385);
FORCEPROP 2 LAST CDS_LIB pure_quanta_power
J 0
(-6900 2325);
PAINT MONO (-6900 2325);
DISPLAY INVISIBLE (-6900 2325);
FORCEPROP 1 LAST HDL_POWER GND
J 1
(-6875 2250);
DISPLAY 0.872340 (-6875 2250);
PAINT GREEN (-6875 2250);
DISPLAY INVISIBLE (-6875 2250);
FORCEPROP 1 LAST PATH I16
J 0
(-6825 2325);
DISPLAY 0.872340 (-6825 2325);
PAINT AQUA (-6825 2325);
DISPLAY INVISIBLE (-6825 2325);
FORCEADD Q_RES..1
(-6525 2125);
FORCEPROP 1 LAST LOCATION R2987
J 0
(-6700 2125);
DISPLAY 0.638298 (-6700 2125);
FORCEPROP 2 LAST $SEC 1
J 0
(-6575 2325);
DISPLAY 0.680851 (-6575 2325);
PAINT MONO (-6575 2325);
DISPLAY INVISIBLE (-6575 2325);
FORCEPROP 2 LAST CDS_SEC 1
J 0
(-6575 2325);
DISPLAY 1.021277 (-6575 2325);
DISPLAY INVISIBLE (-6575 2325);
FORCEPROP 1 LASTPIN (-6625 2125) $PN 1
J 0
(-6613 2137);
DISPLAY 0.787234 (-6613 2137);
PAINT MONO (-6613 2137);
FORCEPROP 1 LASTPIN (-6425 2125) $PN 2
J 0
(-6463 2137);
DISPLAY 0.787234 (-6463 2137);
PAINT MONO (-6463 2137);
FORCEPROP 1 LAST VALUE 0
J 2
(-6375 2125);
DISPLAY 0.510638 (-6375 2125);
FORCEPROP 1 LAST TOLERANCE 5%
J 0
(-6300 2125);
DISPLAY 0.510638 (-6300 2125);
FORCEPROP 1 LAST PACK_TYPE 0402LF
J 0
(-6625 2025);
DISPLAY 0.404255 (-6625 2025);
FORCEPROP 1 LAST WATTAGE 1/16W
J 2
(-6400 2025);
DISPLAY 0.404255 (-6400 2025);
FORCEPROP 1 LAST MATERIAL EMPTY
J 0
(-6225 2125);
DISPLAY 0.510638 (-6225 2125);
PAINT RED (-6225 2125);
FORCEPROP 2 LAST CDS_LIB pure_quanta
J 0
(-6525 2125);
DISPLAY INVISIBLE (-6525 2125);
FORCEPROP 1 LAST PATH I17
J 0
(-6575 2275);
DISPLAY 0.978723 (-6575 2275);
PAINT WHITE (-6575 2275);
DISPLAY INVISIBLE (-6575 2275);
FORCEPROP 1 LAST PART_NUMBER CS00002JB13
J 0
(-6625 2075);
DISPLAY 0.404255 (-6625 2075);
DISPLAY INVISIBLE (-6625 2075);
FORCEADD Q_RES..1
(-6525 2200);
FORCEPROP 1 LAST LOCATION R2986
J 0
(-6700 2200);
DISPLAY 0.638298 (-6700 2200);
FORCEPROP 0 LAST $SEC 1
J 0
(-6400 2300);
DISPLAY 0.680851 (-6400 2300);
PAINT MONO (-6400 2300);
DISPLAY INVISIBLE (-6400 2300);
FORCEPROP 0 LAST CDS_SEC 1
J 0
(-6400 2300);
DISPLAY 1.021277 (-6400 2300);
DISPLAY INVISIBLE (-6400 2300);
FORCEPROP 1 LASTPIN (-6625 2200) $PN 1
J 0
(-6613 2212);
DISPLAY 0.787234 (-6613 2212);
PAINT MONO (-6613 2212);
FORCEPROP 1 LASTPIN (-6425 2200) $PN 2
J 0
(-6463 2212);
DISPLAY 0.787234 (-6463 2212);
PAINT MONO (-6463 2212);
FORCEPROP 1 LAST VALUE 0
J 2
(-6375 2200);
DISPLAY 0.510638 (-6375 2200);
FORCEPROP 1 LAST MATERIAL EMPTY
J 0
(-6225 2200);
DISPLAY 0.510638 (-6225 2200);
PAINT RED (-6225 2200);
FORCEPROP 2 LAST CDS_LIB pure_quanta
J 0
(-6525 2200);
DISPLAY INVISIBLE (-6525 2200);
FORCEPROP 1 LAST PACK_TYPE 0402LF
J 0
(-6625 2100);
DISPLAY 0.404255 (-6625 2100);
DISPLAY INVISIBLE (-6625 2100);
FORCEPROP 1 LAST TOLERANCE 5%
J 0
(-6300 2200);
DISPLAY 0.510638 (-6300 2200);
DISPLAY INVISIBLE (-6300 2200);
FORCEPROP 1 LAST WATTAGE 1/16W
J 2
(-6400 2100);
DISPLAY 0.404255 (-6400 2100);
DISPLAY INVISIBLE (-6400 2100);
FORCEPROP 1 LAST PATH I18
J 0
(-6575 2350);
DISPLAY 0.978723 (-6575 2350);
PAINT WHITE (-6575 2350);
DISPLAY INVISIBLE (-6575 2350);
FORCEPROP 1 LAST PART_NUMBER CS00002JB13
J 0
(-6625 2150);
DISPLAY 0.404255 (-6625 2150);
DISPLAY INVISIBLE (-6625 2150);
FORCEADD UNIVERSAL_GND..1
(-6700 3475);
FORCEPROP 3 LASTPIN (-6700 3525) SIG_NAME GND\g
J 0
(-6690 3535);
DISPLAY 0.659574 (-6690 3535);
PAINT MONO (-6690 3535);
DISPLAY INVISIBLE (-6690 3535);
FORCEPROP 2 LAST CDS_LIB pure_quanta_power
J 0
(-6700 3475);
DISPLAY INVISIBLE (-6700 3475);
FORCEPROP 1 LAST HDL_POWER GND
J 1
(-6675 3400);
DISPLAY 0.872340 (-6675 3400);
PAINT GREEN (-6675 3400);
DISPLAY INVISIBLE (-6675 3400);
FORCEPROP 1 LAST PATH I19
J 0
(-6625 3475);
DISPLAY 0.872340 (-6625 3475);
PAINT AQUA (-6625 3475);
DISPLAY INVISIBLE (-6625 3475);
FORCEADD OFFPAGE..4
R 2
(-8700 2750);
FORCEPROP 2 LAST $XR1 249 
J 0
(-9071 2750);
DISPLAY 0.638298 (-9071 2750);
PAINT MONO (-9071 2750);
FORCEPROP 2 LAST $XR0 82 
J 0
(-8951 2750);
DISPLAY 0.638298 (-8951 2750);
PAINT MONO (-8951 2750);
FORCEPROP 2 LAST CDS_LIB standard
J 0
(-8700 2750);
DISPLAY INVISIBLE (-8700 2750);
FORCEPROP 1 LAST OFFPAGE TRUE
J 2
(-9025 2625);
DISPLAY 0.872340 (-9025 2625);
DISPLAY INVISIBLE (-9025 2625);
FORCEPROP 1 LAST COMMENT_BODY TRUE
J 2
(-8675 2650);
DISPLAY 0.872340 (-8675 2650);
PAINT GREEN (-8675 2650);
DISPLAY INVISIBLE (-8675 2650);
FORCEPROP 2 LAST PATH I2
J 0
(-8950 2800);
DISPLAY 0.680851 (-8950 2800);
DISPLAY INVISIBLE (-8950 2800);
FORCEADD OFFPAGE..6
(-6925 4000);
FORCEPROP 2 LAST $XR1 151 
J 0
(-7355 4000);
DISPLAY 0.638298 (-7355 4000);
PAINT MONO (-7355 4000);
FORCEPROP 2 LAST $XR0 150 
J 0
(-7235 4000);
DISPLAY 0.638298 (-7235 4000);
PAINT MONO (-7235 4000);
FORCEPROP 2 LAST CDS_LIB standard
J 0
(-6925 4000);
PAINT MONO (-6925 4000);
DISPLAY INVISIBLE (-6925 4000);
FORCEPROP 1 LAST OFFPAGE TRUE
J 0
(-6600 3875);
DISPLAY 0.872340 (-6600 3875);
DISPLAY INVISIBLE (-6600 3875);
FORCEPROP 1 LAST COMMENT_BODY TRUE
J 0
(-6825 3925);
DISPLAY 0.872340 (-6825 3925);
PAINT GREEN (-6825 3925);
DISPLAY INVISIBLE (-6825 3925);
FORCEPROP 2 LAST PATH I20
J 0
(-7200 4050);
DISPLAY 0.680851 (-7200 4050);
DISPLAY INVISIBLE (-7200 4050);
FORCEADD OFFPAGE..1
(-6925 3900);
FORCEPROP 2 LAST $XR1 151 
J 0
(-7327 3900);
DISPLAY 0.638298 (-7327 3900);
PAINT MONO (-7327 3900);
FORCEPROP 2 LAST $XR0 150 
J 0
(-7207 3900);
DISPLAY 0.638298 (-7207 3900);
PAINT MONO (-7207 3900);
FORCEPROP 2 LAST CDS_LIB standard
J 0
(-6925 3900);
PAINT MONO (-6925 3900);
DISPLAY INVISIBLE (-6925 3900);
FORCEPROP 1 LAST OFFPAGE TRUE
J 0
(-6600 3775);
DISPLAY 0.872340 (-6600 3775);
DISPLAY INVISIBLE (-6600 3775);
FORCEPROP 1 LAST COMMENT_BODY TRUE
J 0
(-6800 3800);
DISPLAY 0.872340 (-6800 3800);
PAINT GREEN (-6800 3800);
DISPLAY INVISIBLE (-6800 3800);
FORCEPROP 2 LAST PATH I21
J 0
(-6875 3975);
DISPLAY 0.680851 (-6875 3975);
DISPLAY INVISIBLE (-6875 3975);
FORCEADD OFFPAGE..4
R 2
(-6925 4100);
FORCEPROP 2 LAST $XR1 249 
J 0
(-7296 4100);
DISPLAY 0.638298 (-7296 4100);
PAINT MONO (-7296 4100);
FORCEPROP 2 LAST $XR0 82 
J 0
(-7176 4100);
DISPLAY 0.638298 (-7176 4100);
PAINT MONO (-7176 4100);
FORCEPROP 2 LAST CDS_LIB standard
J 0
(-6925 4100);
DISPLAY INVISIBLE (-6925 4100);
FORCEPROP 1 LAST OFFPAGE TRUE
J 2
(-7250 3975);
DISPLAY 0.872340 (-7250 3975);
DISPLAY INVISIBLE (-7250 3975);
FORCEPROP 1 LAST COMMENT_BODY TRUE
J 2
(-6900 4000);
DISPLAY 0.872340 (-6900 4000);
PAINT GREEN (-6900 4000);
DISPLAY INVISIBLE (-6900 4000);
FORCEPROP 2 LAST PATH I22
J 0
(-7200 4150);
DISPLAY 0.680851 (-7200 4150);
DISPLAY INVISIBLE (-7200 4150);
FORCEADD Q_RES..2
(-6700 3675);
FORCEPROP 1 LAST LOCATION R4603
J 0
(-6655 3800);
DISPLAY 0.978723 (-6655 3800);
FORCEPROP 0 LAST $SEC 1
J 0
(-6650 3850);
DISPLAY 0.680851 (-6650 3850);
PAINT MONO (-6650 3850);
DISPLAY INVISIBLE (-6650 3850);
FORCEPROP 0 LAST CDS_SEC 1
J 0
(-6650 3850);
DISPLAY 1.021277 (-6650 3850);
DISPLAY INVISIBLE (-6650 3850);
FORCEPROP 1 LASTPIN (-6700 3775) $PN 1
J 0
(-6695 3737);
DISPLAY 0.787234 (-6695 3737);
PAINT MONO (-6695 3737);
FORCEPROP 1 LASTPIN (-6700 3575) $PN 2
J 0
(-6695 3585);
DISPLAY 0.787234 (-6695 3585);
PAINT MONO (-6695 3585);
FORCEPROP 1 LAST VALUE 10K
J 0
(-6655 3750);
DISPLAY 0.510638 (-6655 3750);
FORCEPROP 1 LAST TOLERANCE 1%
J 0
(-6655 3700);
DISPLAY 0.510638 (-6655 3700);
FORCEPROP 1 LAST WATTAGE 1/16W
J 0
(-6660 3650);
DISPLAY 0.510638 (-6660 3650);
FORCEPROP 1 LAST MATERIAL CHIP
J 0
(-6660 3600);
DISPLAY 0.510638 (-6660 3600);
FORCEPROP 1 LAST PACK_TYPE 0402LF
J 0
(-6660 3550);
DISPLAY 0.510638 (-6660 3550);
FORCEPROP 2 LAST CDS_LIB pure_quanta
J 0
(-6700 3675);
DISPLAY INVISIBLE (-6700 3675);
FORCEPROP 1 LAST PATH I23
J 0
(-6650 3850);
DISPLAY 0.978723 (-6650 3850);
PAINT WHITE (-6650 3850);
DISPLAY INVISIBLE (-6650 3850);
FORCEPROP 1 LAST PART_NUMBER CS31002FB08
J 0
(-6660 3500);
DISPLAY 0.510638 (-6660 3500);
DISPLAY INVISIBLE (-6660 3500);
FORCEADD Q_RES..1
(-5700 1225);
FORCEPROP 1 LAST LOCATION R3112
J 0
(-5925 1225);
DISPLAY 0.638298 (-5925 1225);
FORCEPROP 0 LAST $SEC 1
J 0
(-5925 1275);
DISPLAY 0.680851 (-5925 1275);
PAINT MONO (-5925 1275);
DISPLAY INVISIBLE (-5925 1275);
FORCEPROP 0 LAST CDS_SEC 1
J 0
(-5925 1275);
DISPLAY 1.021277 (-5925 1275);
DISPLAY INVISIBLE (-5925 1275);
FORCEPROP 1 LASTPIN (-5800 1225) $PN 1
J 0
(-5788 1237);
DISPLAY 0.787234 (-5788 1237);
PAINT MONO (-5788 1237);
FORCEPROP 1 LASTPIN (-5600 1225) $PN 2
J 0
(-5638 1237);
DISPLAY 0.787234 (-5638 1237);
PAINT MONO (-5638 1237);
FORCEPROP 1 LAST VALUE 33.2
J 2
(-5500 1225);
DISPLAY 0.510638 (-5500 1225);
FORCEPROP 1 LAST MATERIAL CHIP
J 0
(-5400 1225);
DISPLAY 0.510638 (-5400 1225);
FORCEPROP 1 LAST TOLERANCE 1%
J 0
(-5475 1225);
DISPLAY 0.510638 (-5475 1225);
FORCEPROP 2 LAST CDS_LIB pure_quanta
J 0
(-5700 1225);
DISPLAY INVISIBLE (-5700 1225);
FORCEPROP 1 LAST PACK_TYPE 0402LF
J 0
(-5825 1325);
DISPLAY 0.404255 (-5825 1325);
DISPLAY INVISIBLE (-5825 1325);
FORCEPROP 1 LAST WATTAGE 1/16W
J 2
(-5600 1325);
DISPLAY 0.404255 (-5600 1325);
DISPLAY INVISIBLE (-5600 1325);
FORCEPROP 1 LAST PATH I25
J 0
(-5750 1375);
DISPLAY 0.978723 (-5750 1375);
PAINT WHITE (-5750 1375);
DISPLAY INVISIBLE (-5750 1375);
FORCEPROP 1 LAST PART_NUMBER CS03322FB03
J 0
(-5825 1275);
DISPLAY 0.404255 (-5825 1275);
DISPLAY INVISIBLE (-5825 1275);
FORCEADD Q_RES..1
(-5700 1325);
FORCEPROP 1 LAST LOCATION R2676
J 0
(-5925 1325);
DISPLAY 0.638298 (-5925 1325);
FORCEPROP 0 LAST $SEC 1
J 0
(-5575 1425);
DISPLAY 0.680851 (-5575 1425);
PAINT MONO (-5575 1425);
DISPLAY INVISIBLE (-5575 1425);
FORCEPROP 0 LAST CDS_SEC 1
J 0
(-5575 1425);
DISPLAY 1.021277 (-5575 1425);
DISPLAY INVISIBLE (-5575 1425);
FORCEPROP 1 LASTPIN (-5800 1325) $PN 1
J 0
(-5788 1337);
DISPLAY 0.787234 (-5788 1337);
PAINT MONO (-5788 1337);
FORCEPROP 1 LASTPIN (-5600 1325) $PN 2
J 0
(-5638 1337);
DISPLAY 0.787234 (-5638 1337);
PAINT MONO (-5638 1337);
FORCEPROP 1 LAST WATTAGE 1/16W
J 2
(-5575 1375);
DISPLAY 0.404255 (-5575 1375);
FORCEPROP 1 LAST PACK_TYPE 0402LF
J 0
(-5800 1375);
DISPLAY 0.404255 (-5800 1375);
FORCEPROP 1 LAST MATERIAL CHIP
J 0
(-5400 1325);
DISPLAY 0.510638 (-5400 1325);
FORCEPROP 1 LAST TOLERANCE 5%
J 0
(-5475 1325);
DISPLAY 0.510638 (-5475 1325);
FORCEPROP 1 LAST VALUE 0
J 2
(-5550 1325);
DISPLAY 0.510638 (-5550 1325);
FORCEPROP 2 LAST CDS_LIB pure_quanta
J 0
(-5700 1325);
DISPLAY INVISIBLE (-5700 1325);
FORCEPROP 1 LAST PATH I26
J 0
(-5750 1475);
DISPLAY 0.978723 (-5750 1475);
PAINT WHITE (-5750 1475);
DISPLAY INVISIBLE (-5750 1475);
FORCEPROP 1 LAST PART_NUMBER CS00002JB13
J 0
(-5800 1425);
DISPLAY 0.404255 (-5800 1425);
DISPLAY INVISIBLE (-5800 1425);
FORCEADD Q_RES..1
(-3975 475);
FORCEPROP 1 LAST LOCATION R2706
J 0
(-4175 475);
DISPLAY 0.638298 (-4175 475);
FORCEPROP 0 LAST $SEC 1
J 0
(-3850 575);
DISPLAY 0.680851 (-3850 575);
PAINT MONO (-3850 575);
DISPLAY INVISIBLE (-3850 575);
FORCEPROP 0 LAST CDS_SEC 1
J 0
(-3850 575);
DISPLAY 1.021277 (-3850 575);
DISPLAY INVISIBLE (-3850 575);
FORCEPROP 1 LASTPIN (-4075 475) $PN 1
J 0
(-4063 487);
DISPLAY 0.787234 (-4063 487);
PAINT MONO (-4063 487);
FORCEPROP 1 LASTPIN (-3875 475) $PN 2
J 0
(-3913 487);
DISPLAY 0.787234 (-3913 487);
PAINT MONO (-3913 487);
FORCEPROP 1 LAST VALUE 0
J 2
(-3825 475);
DISPLAY 0.510638 (-3825 475);
FORCEPROP 1 LAST MATERIAL CHIP
J 0
(-3675 475);
DISPLAY 0.510638 (-3675 475);
FORCEPROP 2 LAST CDS_LIB pure_quanta
J 0
(-3975 475);
DISPLAY INVISIBLE (-3975 475);
FORCEPROP 1 LAST PACK_TYPE 0402LF
J 0
(-4075 375);
DISPLAY 0.404255 (-4075 375);
DISPLAY INVISIBLE (-4075 375);
FORCEPROP 1 LAST TOLERANCE 5%
J 0
(-3750 475);
DISPLAY 0.510638 (-3750 475);
DISPLAY INVISIBLE (-3750 475);
FORCEPROP 1 LAST WATTAGE 1/16W
J 2
(-3850 375);
DISPLAY 0.404255 (-3850 375);
DISPLAY INVISIBLE (-3850 375);
FORCEPROP 1 LAST PATH I27
J 0
(-4025 625);
DISPLAY 0.978723 (-4025 625);
PAINT WHITE (-4025 625);
DISPLAY INVISIBLE (-4025 625);
FORCEPROP 1 LAST PART_NUMBER CS00002JB13
J 0
(-4075 425);
DISPLAY 0.404255 (-4075 425);
DISPLAY INVISIBLE (-4075 425);
FORCEADD Q_RES..1
(-3975 400);
FORCEPROP 1 LAST LOCATION R2725
J 0
(-4175 400);
DISPLAY 0.638298 (-4175 400);
FORCEPROP 2 LAST $SEC 1
J 0
(-4025 600);
DISPLAY 0.680851 (-4025 600);
PAINT MONO (-4025 600);
DISPLAY INVISIBLE (-4025 600);
FORCEPROP 2 LAST CDS_SEC 1
J 0
(-4025 600);
DISPLAY 1.021277 (-4025 600);
DISPLAY INVISIBLE (-4025 600);
FORCEPROP 1 LASTPIN (-4075 400) $PN 1
J 0
(-4063 412);
DISPLAY 0.787234 (-4063 412);
PAINT MONO (-4063 412);
FORCEPROP 1 LASTPIN (-3875 400) $PN 2
J 0
(-3913 412);
DISPLAY 0.787234 (-3913 412);
PAINT MONO (-3913 412);
FORCEPROP 1 LAST TOLERANCE 5%
J 0
(-3750 400);
DISPLAY 0.510638 (-3750 400);
FORCEPROP 1 LAST WATTAGE 1/16W
J 2
(-3850 300);
DISPLAY 0.404255 (-3850 300);
FORCEPROP 1 LAST VALUE 0
J 2
(-3825 400);
DISPLAY 0.510638 (-3825 400);
FORCEPROP 1 LAST PACK_TYPE 0402LF
J 0
(-4075 300);
DISPLAY 0.404255 (-4075 300);
FORCEPROP 1 LAST MATERIAL CHIP
J 0
(-3675 400);
DISPLAY 0.510638 (-3675 400);
FORCEPROP 2 LAST CDS_LIB pure_quanta
J 0
(-3975 400);
DISPLAY INVISIBLE (-3975 400);
FORCEPROP 1 LAST PATH I28
J 0
(-4025 550);
DISPLAY 0.978723 (-4025 550);
PAINT WHITE (-4025 550);
DISPLAY INVISIBLE (-4025 550);
FORCEPROP 1 LAST PART_NUMBER CS00002JB13
J 0
(-4075 350);
DISPLAY 0.404255 (-4075 350);
DISPLAY INVISIBLE (-4075 350);
FORCEADD UNIVERSAL_GND..1
(-4475 900);
FORCEPROP 3 LASTPIN (-4475 950) SIG_NAME GND\g
J 0
(-4465 960);
DISPLAY 0.659574 (-4465 960);
PAINT MONO (-4465 960);
DISPLAY INVISIBLE (-4465 960);
FORCEPROP 2 LAST CDS_LIB pure_quanta_power
J 0
(-4475 900);
DISPLAY INVISIBLE (-4475 900);
FORCEPROP 1 LAST HDL_POWER GND
J 1
(-4450 825);
DISPLAY 0.872340 (-4450 825);
PAINT GREEN (-4450 825);
DISPLAY INVISIBLE (-4450 825);
FORCEPROP 1 LAST PATH I29
J 0
(-4400 900);
DISPLAY 0.872340 (-4400 900);
PAINT AQUA (-4400 900);
DISPLAY INVISIBLE (-4400 900);
FORCEADD OFFPAGE..6
(-8700 2650);
FORCEPROP 2 LAST $XR1 151 
J 0
(-9100 2650);
DISPLAY 0.638298 (-9100 2650);
PAINT MONO (-9100 2650);
FORCEPROP 2 LAST $XR0 150 
J 0
(-8980 2650);
DISPLAY 0.638298 (-8980 2650);
PAINT MONO (-8980 2650);
FORCEPROP 2 LAST CDS_LIB standard
J 0
(-8700 2650);
PAINT MONO (-8700 2650);
DISPLAY INVISIBLE (-8700 2650);
FORCEPROP 1 LAST OFFPAGE TRUE
J 0
(-8375 2525);
DISPLAY 0.872340 (-8375 2525);
DISPLAY INVISIBLE (-8375 2525);
FORCEPROP 1 LAST COMMENT_BODY TRUE
J 0
(-8600 2575);
DISPLAY 0.872340 (-8600 2575);
PAINT GREEN (-8600 2575);
DISPLAY INVISIBLE (-8600 2575);
FORCEPROP 2 LAST PATH I3
J 0
(-8650 2725);
DISPLAY 0.680851 (-8650 2725);
DISPLAY INVISIBLE (-8650 2725);
FORCEADD LTC4307CMS8..1
(-3925 1175);
FORCEPROP 1 LAST LOCATION U176
J 0
(-4175 1480);
DISPLAY 0.723404 (-4175 1480);
PAINT GREEN (-4175 1480);
FORCEPROP 0 LAST $SEC 1
J 0
(-4175 1625);
DISPLAY 0.680851 (-4175 1625);
PAINT MONO (-4175 1625);
DISPLAY INVISIBLE (-4175 1625);
FORCEPROP 0 LAST CDS_SEC 1
J 0
(-4175 1625);
DISPLAY 1.021277 (-4175 1625);
DISPLAY INVISIBLE (-4175 1625);
FORCEPROP 0 LASTPIN (-4325 1325) $PN 1
J 2
(-4335 1335);
DISPLAY 0.680851 (-4335 1335);
PAINT MONO (-4335 1335);
FORCEPROP 0 LASTPIN (-4325 1025) $PN 4
J 2
(-4335 1035);
DISPLAY 0.680851 (-4335 1035);
PAINT MONO (-4335 1035);
FORCEPROP 0 LASTPIN (-3525 1025) $PN 5
J 0
(-3515 1035);
DISPLAY 0.680851 (-3515 1035);
PAINT MONO (-3515 1035);
FORCEPROP 0 LASTPIN (-4325 1225) $PN 3
J 2
(-4335 1235);
DISPLAY 0.680851 (-4335 1235);
PAINT MONO (-4335 1235);
FORCEPROP 0 LASTPIN (-3525 1225) $PN 2
J 0
(-3515 1235);
DISPLAY 0.680851 (-3515 1235);
PAINT MONO (-3515 1235);
FORCEPROP 0 LASTPIN (-4325 1125) $PN 6
J 2
(-4335 1135);
DISPLAY 0.680851 (-4335 1135);
PAINT MONO (-4335 1135);
FORCEPROP 0 LASTPIN (-3525 1125) $PN 7
J 0
(-3515 1135);
DISPLAY 0.680851 (-3515 1135);
PAINT MONO (-3515 1135);
FORCEPROP 0 LASTPIN (-3525 1325) $PN 8
J 0
(-3515 1335);
DISPLAY 0.680851 (-3515 1335);
PAINT MONO (-3515 1335);
FORCEPROP 2 LAST PART_TYPE SMLF
J 0
(-4175 1575);
DISPLAY 1.021277 (-4175 1575);
FORCEPROP 1 LAST MATERIAL EMPTY
J 0
(-4175 1385);
DISPLAY 0.723404 (-4175 1385);
PAINT RED (-4175 1385);
FORCEPROP 2 LAST VALUE LTC4307CMS8
J 0
(-4175 1525);
DISPLAY 1.021277 (-4175 1525);
FORCEPROP 1 LAST NEEDS_NO_SIZE TRUE
J 0
(-3925 1175);
DISPLAY 0.468085 (-3925 1175);
PAINT GREEN (-3925 1175);
DISPLAY INVISIBLE (-3925 1175);
FORCEPROP 2 LAST CDS_LIB pure_quanta
J 0
(-3925 1175);
DISPLAY INVISIBLE (-3925 1175);
FORCEPROP 1 LAST PATH I30
J 0
(-3700 1380);
DISPLAY 0.723404 (-3700 1380);
PAINT GREEN (-3700 1380);
DISPLAY INVISIBLE (-3700 1380);
FORCEPROP 1 LAST PART_NUMBER AL004307000
J 0
(-4175 1435);
DISPLAY 0.723404 (-4175 1435);
PAINT GREEN (-4175 1435);
DISPLAY INVISIBLE (-4175 1435);
FORCEADD UNIVERSAL_GND..1
(-5775 2775);
FORCEPROP 3 LASTPIN (-5775 2825) SIG_NAME GND\g
J 0
(-5765 2835);
DISPLAY 0.659574 (-5765 2835);
PAINT MONO (-5765 2835);
DISPLAY INVISIBLE (-5765 2835);
FORCEPROP 2 LAST CDS_LIB pure_quanta_power
J 0
(-5775 2775);
PAINT MONO (-5775 2775);
DISPLAY INVISIBLE (-5775 2775);
FORCEPROP 1 LAST HDL_POWER GND
J 1
(-5750 2700);
DISPLAY 0.872340 (-5750 2700);
PAINT GREEN (-5750 2700);
DISPLAY INVISIBLE (-5750 2700);
FORCEPROP 1 LAST PATH I31
J 0
(-5700 2775);
DISPLAY 0.872340 (-5700 2775);
PAINT AQUA (-5700 2775);
DISPLAY INVISIBLE (-5700 2775);
FORCEADD Q_CAP..1
(-5775 3000);
FORCEPROP 1 LAST LOCATION C1796
J 0
(-5725 3100);
DISPLAY 0.978723 (-5725 3100);
FORCEPROP 2 LAST $SEC 1
J 0
(-5725 3200);
DISPLAY 0.680851 (-5725 3200);
PAINT MONO (-5725 3200);
DISPLAY INVISIBLE (-5725 3200);
FORCEPROP 2 LAST CDS_SEC 1
J 0
(-5725 3200);
DISPLAY 1.021277 (-5725 3200);
DISPLAY INVISIBLE (-5725 3200);
FORCEPROP 1 LASTPIN (-5775 3100) $PN 1
J 0
(-5765 3080);
DISPLAY 0.787234 (-5765 3080);
FORCEPROP 1 LASTPIN (-5775 2900) $PN 2
J 0
(-5765 2880);
DISPLAY 0.787234 (-5765 2880);
FORCEPROP 1 LAST PACK_TYPE 0402
J 0
(-5725 2800);
DISPLAY 0.510638 (-5725 2800);
FORCEPROP 1 LAST MATERIAL X7R
J 0
(-5725 2900);
DISPLAY 0.510638 (-5725 2900);
FORCEPROP 1 LAST VOLTAGE 25V
J 0
(-5725 3000);
DISPLAY 0.510638 (-5725 3000);
FORCEPROP 1 LAST TOLERANCE 10%
J 0
(-5725 2950);
DISPLAY 0.510638 (-5725 2950);
FORCEPROP 1 LAST VALUE 0.1UF
J 0
(-5725 3050);
DISPLAY 0.510638 (-5725 3050);
FORCEPROP 2 LAST CDS_LIB pure_quanta
J 0
(-5775 3000);
PAINT MONO (-5775 3000);
DISPLAY INVISIBLE (-5775 3000);
FORCEPROP 1 LAST PATH I32
J 0
(-5725 3150);
DISPLAY 0.978723 (-5725 3150);
PAINT WHITE (-5725 3150);
DISPLAY INVISIBLE (-5725 3150);
FORCEPROP 1 LAST PART_NUMBER CH4104K1B00
J 0
(-5725 2850);
DISPLAY 0.510638 (-5725 2850);
DISPLAY INVISIBLE (-5725 2850);
FORCEADD UNIVERSAL_POWER..1
(-5950 3300);
FORCEPROP 3 LASTPIN (-5950 3250) SIG_NAME P3V3_AUX\g
J 0
(-5940 3260);
DISPLAY 0.659574 (-5940 3260);
PAINT MONO (-5940 3260);
DISPLAY INVISIBLE (-5940 3260);
FORCEPROP 1 LAST HDL_POWER P3V3_AUX
J 1
(-5950 3400);
DISPLAY 0.872340 (-5950 3400);
PAINT GREEN (-5950 3400);
FORCEPROP 2 LAST CDS_LIB pure_quanta_power
J 0
(-5950 3300);
PAINT MONO (-5950 3300);
DISPLAY INVISIBLE (-5950 3300);
FORCEPROP 1 LAST PATH I33
J 0
(-5900 3325);
DISPLAY 0.872340 (-5900 3325);
PAINT AQUA (-5900 3325);
DISPLAY INVISIBLE (-5900 3325);
FORCEADD Q_RES..1
(-5750 3900);
FORCEPROP 1 LAST LOCATION R3110
J 0
(-5950 3900);
DISPLAY 0.510638 (-5950 3900);
FORCEPROP 0 LAST $SEC 1
J 0
(-5800 4000);
DISPLAY 0.680851 (-5800 4000);
PAINT MONO (-5800 4000);
DISPLAY INVISIBLE (-5800 4000);
FORCEPROP 0 LAST CDS_SEC 1
J 0
(-5800 4000);
DISPLAY 1.021277 (-5800 4000);
DISPLAY INVISIBLE (-5800 4000);
FORCEPROP 1 LASTPIN (-5850 3900) $PN 1
J 0
(-5838 3912);
DISPLAY 0.787234 (-5838 3912);
PAINT MONO (-5838 3912);
FORCEPROP 1 LASTPIN (-5650 3900) $PN 2
J 0
(-5688 3912);
DISPLAY 0.787234 (-5688 3912);
PAINT MONO (-5688 3912);
FORCEPROP 1 LAST WATTAGE 1/16W
J 2
(-5600 3850);
DISPLAY 0.404255 (-5600 3850);
FORCEPROP 1 LAST MATERIAL CHIP
J 0
(-5500 3900);
DISPLAY 0.510638 (-5500 3900);
FORCEPROP 1 LAST TOLERANCE 5%
J 0
(-5550 3900);
DISPLAY 0.510638 (-5550 3900);
FORCEPROP 1 LAST PACK_TYPE 0402LF
J 0
(-5825 3850);
DISPLAY 0.404255 (-5825 3850);
FORCEPROP 1 LAST VALUE 0
J 2
(-5600 3900);
DISPLAY 0.510638 (-5600 3900);
FORCEPROP 2 LAST CDS_LIB pure_quanta
J 0
(-5750 3900);
DISPLAY INVISIBLE (-5750 3900);
FORCEPROP 1 LAST PATH I34
J 0
(-5800 4050);
DISPLAY 0.978723 (-5800 4050);
PAINT WHITE (-5800 4050);
DISPLAY INVISIBLE (-5800 4050);
FORCEPROP 1 LAST PART_NUMBER CS00002JB13
J 0
(-5825 3800);
DISPLAY 0.404255 (-5825 3800);
DISPLAY INVISIBLE (-5825 3800);
FORCEADD Q_RES..1
(-5750 4000);
FORCEPROP 1 LAST LOCATION R3109
J 0
(-5950 4000);
DISPLAY 0.510638 (-5950 4000);
FORCEPROP 0 LAST $SEC 1
J 0
(-5800 4100);
DISPLAY 0.680851 (-5800 4100);
PAINT MONO (-5800 4100);
DISPLAY INVISIBLE (-5800 4100);
FORCEPROP 0 LAST CDS_SEC 1
J 0
(-5800 4100);
DISPLAY 1.021277 (-5800 4100);
DISPLAY INVISIBLE (-5800 4100);
FORCEPROP 1 LASTPIN (-5850 4000) $PN 1
J 0
(-5838 4012);
DISPLAY 0.787234 (-5838 4012);
PAINT MONO (-5838 4012);
FORCEPROP 1 LASTPIN (-5650 4000) $PN 2
J 0
(-5688 4012);
DISPLAY 0.787234 (-5688 4012);
PAINT MONO (-5688 4012);
FORCEPROP 1 LAST TOLERANCE 5%
J 0
(-5550 4000);
DISPLAY 0.510638 (-5550 4000);
FORCEPROP 1 LAST VALUE 0
J 2
(-5600 4000);
DISPLAY 0.510638 (-5600 4000);
FORCEPROP 1 LAST MATERIAL CHIP
J 0
(-5500 4000);
DISPLAY 0.510638 (-5500 4000);
FORCEPROP 2 LAST CDS_LIB pure_quanta
J 0
(-5750 4000);
DISPLAY INVISIBLE (-5750 4000);
FORCEPROP 1 LAST PACK_TYPE 0402LF
J 0
(-5900 3950);
DISPLAY 0.404255 (-5900 3950);
DISPLAY INVISIBLE (-5900 3950);
FORCEPROP 1 LAST WATTAGE 1/16W
J 2
(-5600 3950);
DISPLAY 0.404255 (-5600 3950);
DISPLAY INVISIBLE (-5600 3950);
FORCEPROP 1 LAST PATH I35
J 0
(-5800 4150);
DISPLAY 0.978723 (-5800 4150);
PAINT WHITE (-5800 4150);
DISPLAY INVISIBLE (-5800 4150);
FORCEPROP 1 LAST PART_NUMBER CS00002JB13
J 0
(-5775 3925);
DISPLAY 0.404255 (-5775 3925);
DISPLAY INVISIBLE (-5775 3925);
FORCEADD Q_RES..2
(-5025 2975);
FORCEPROP 1 LAST LOCATION R3521
J 0
(-4980 3100);
DISPLAY 0.978723 (-4980 3100);
FORCEPROP 0 LAST $SEC 1
J 0
(-4975 3150);
DISPLAY 0.680851 (-4975 3150);
PAINT MONO (-4975 3150);
DISPLAY INVISIBLE (-4975 3150);
FORCEPROP 0 LAST CDS_SEC 1
J 0
(-4975 3150);
DISPLAY 1.021277 (-4975 3150);
DISPLAY INVISIBLE (-4975 3150);
FORCEPROP 1 LASTPIN (-5025 3075) $PN 1
J 0
(-5020 3037);
DISPLAY 0.787234 (-5020 3037);
PAINT MONO (-5020 3037);
FORCEPROP 1 LASTPIN (-5025 2875) $PN 2
J 0
(-5020 2885);
DISPLAY 0.787234 (-5020 2885);
PAINT MONO (-5020 2885);
FORCEPROP 1 LAST TOLERANCE 1%
J 0
(-4980 3000);
DISPLAY 0.404255 (-4980 3000);
FORCEPROP 1 LAST VALUE 54.9K
J 0
(-4980 3050);
DISPLAY 0.404255 (-4980 3050);
FORCEPROP 1 LAST PACK_TYPE 0402LF
J 0
(-4985 2800);
DISPLAY 0.404255 (-4985 2800);
FORCEPROP 1 LAST WATTAGE 1/16W
J 0
(-4985 2950);
DISPLAY 0.404255 (-4985 2950);
FORCEPROP 1 LAST MATERIAL CHIP
J 0
(-4985 2900);
DISPLAY 0.404255 (-4985 2900);
FORCEPROP 2 LAST CDS_LIB pure_quanta
J 0
(-5025 2975);
DISPLAY INVISIBLE (-5025 2975);
FORCEPROP 1 LAST PATH I36
J 0
(-4975 3150);
DISPLAY 0.978723 (-4975 3150);
PAINT WHITE (-4975 3150);
DISPLAY INVISIBLE (-4975 3150);
FORCEPROP 1 LAST PART_NUMBER CS35492FB03
J 0
(-4985 2850);
DISPLAY 0.404255 (-4985 2850);
DISPLAY INVISIBLE (-4985 2850);
FORCEADD Q_RES..2
(-4775 2975);
FORCEPROP 1 LAST LOCATION R3522
J 0
(-4730 3100);
DISPLAY 0.978723 (-4730 3100);
FORCEPROP 0 LAST $SEC 1
J 0
(-4725 3150);
DISPLAY 0.680851 (-4725 3150);
PAINT MONO (-4725 3150);
DISPLAY INVISIBLE (-4725 3150);
FORCEPROP 0 LAST CDS_SEC 1
J 0
(-4725 3150);
DISPLAY 1.021277 (-4725 3150);
DISPLAY INVISIBLE (-4725 3150);
FORCEPROP 1 LASTPIN (-4775 3075) $PN 1
J 0
(-4770 3037);
DISPLAY 0.787234 (-4770 3037);
PAINT MONO (-4770 3037);
FORCEPROP 1 LASTPIN (-4775 2875) $PN 2
J 0
(-4770 2885);
DISPLAY 0.787234 (-4770 2885);
PAINT MONO (-4770 2885);
FORCEPROP 1 LAST MATERIAL CHIP
J 0
(-4735 2900);
DISPLAY 0.404255 (-4735 2900);
FORCEPROP 1 LAST TOLERANCE 1%
J 0
(-4730 3000);
DISPLAY 0.404255 (-4730 3000);
FORCEPROP 1 LAST VALUE 54.9K
J 0
(-4730 3050);
DISPLAY 0.404255 (-4730 3050);
FORCEPROP 1 LAST PACK_TYPE 0402LF
J 0
(-4735 2800);
DISPLAY 0.404255 (-4735 2800);
FORCEPROP 1 LAST WATTAGE 1/16W
J 0
(-4735 2950);
DISPLAY 0.404255 (-4735 2950);
FORCEPROP 2 LAST CDS_LIB pure_quanta
J 0
(-4775 2975);
DISPLAY INVISIBLE (-4775 2975);
FORCEPROP 1 LAST PATH I37
J 0
(-4725 3150);
DISPLAY 0.978723 (-4725 3150);
PAINT WHITE (-4725 3150);
DISPLAY INVISIBLE (-4725 3150);
FORCEPROP 1 LAST PART_NUMBER CS35492FB03
J 0
(-4735 2850);
DISPLAY 0.404255 (-4735 2850);
DISPLAY INVISIBLE (-4735 2850);
FORCEADD Q_RES..1
(-4475 2650);
FORCEPROP 1 LAST LOCATION R2990
J 0
(-4700 2650);
DISPLAY 0.638298 (-4700 2650);
FORCEPROP 0 LAST $SEC 1
J 0
(-4375 2775);
DISPLAY 0.680851 (-4375 2775);
PAINT MONO (-4375 2775);
DISPLAY INVISIBLE (-4375 2775);
FORCEPROP 0 LAST CDS_SEC 1
J 0
(-4375 2775);
DISPLAY 1.021277 (-4375 2775);
DISPLAY INVISIBLE (-4375 2775);
FORCEPROP 1 LASTPIN (-4575 2650) $PN 1
J 0
(-4563 2662);
DISPLAY 0.787234 (-4563 2662);
PAINT MONO (-4563 2662);
FORCEPROP 1 LASTPIN (-4375 2650) $PN 2
J 0
(-4413 2662);
DISPLAY 0.787234 (-4413 2662);
PAINT MONO (-4413 2662);
FORCEPROP 1 LAST MATERIAL CHIP
J 0
(-4175 2650);
DISPLAY 0.510638 (-4175 2650);
FORCEPROP 1 LAST VALUE 33.2
J 2
(-4275 2650);
DISPLAY 0.510638 (-4275 2650);
FORCEPROP 1 LAST TOLERANCE 1%
J 0
(-4250 2650);
DISPLAY 0.510638 (-4250 2650);
FORCEPROP 1 LAST WATTAGE 1/16W
J 2
(-4375 2750);
DISPLAY 0.404255 (-4375 2750);
FORCEPROP 1 LAST PACK_TYPE 0402LF
J 0
(-4600 2750);
DISPLAY 0.404255 (-4600 2750);
FORCEPROP 2 LAST CDS_LIB pure_quanta
J 0
(-4475 2650);
DISPLAY INVISIBLE (-4475 2650);
FORCEPROP 1 LAST PATH I38
J 0
(-4525 2800);
DISPLAY 0.978723 (-4525 2800);
PAINT WHITE (-4525 2800);
DISPLAY INVISIBLE (-4525 2800);
FORCEPROP 1 LAST PART_NUMBER CS03322FB03
J 0
(-4600 2700);
DISPLAY 0.404255 (-4600 2700);
DISPLAY INVISIBLE (-4600 2700);
FORCEADD Q_RES..1
(-4475 2550);
FORCEPROP 1 LAST LOCATION R2991
J 0
(-4700 2550);
DISPLAY 0.638298 (-4700 2550);
FORCEPROP 0 LAST $SEC 1
J 0
(-4700 2600);
DISPLAY 0.680851 (-4700 2600);
PAINT MONO (-4700 2600);
DISPLAY INVISIBLE (-4700 2600);
FORCEPROP 0 LAST CDS_SEC 1
J 0
(-4700 2600);
DISPLAY 1.021277 (-4700 2600);
DISPLAY INVISIBLE (-4700 2600);
FORCEPROP 1 LASTPIN (-4575 2550) $PN 1
J 0
(-4563 2562);
DISPLAY 0.787234 (-4563 2562);
PAINT MONO (-4563 2562);
FORCEPROP 1 LASTPIN (-4375 2550) $PN 2
J 0
(-4413 2562);
DISPLAY 0.787234 (-4413 2562);
PAINT MONO (-4413 2562);
FORCEPROP 1 LAST MATERIAL CHIP
J 0
(-4175 2550);
DISPLAY 0.510638 (-4175 2550);
FORCEPROP 1 LAST TOLERANCE 1%
J 0
(-4250 2550);
DISPLAY 0.510638 (-4250 2550);
FORCEPROP 1 LAST VALUE 33.2
J 2
(-4275 2550);
DISPLAY 0.510638 (-4275 2550);
FORCEPROP 1 LAST WATTAGE 1/16W
J 2
(-4375 2650);
DISPLAY 0.404255 (-4375 2650);
DISPLAY INVISIBLE (-4375 2650);
FORCEPROP 1 LAST PACK_TYPE 0402LF
J 0
(-4600 2650);
DISPLAY 0.404255 (-4600 2650);
DISPLAY INVISIBLE (-4600 2650);
FORCEPROP 2 LAST CDS_LIB pure_quanta
J 0
(-4475 2550);
DISPLAY INVISIBLE (-4475 2550);
FORCEPROP 1 LAST PATH I39
J 0
(-4525 2700);
DISPLAY 0.978723 (-4525 2700);
PAINT WHITE (-4525 2700);
DISPLAY INVISIBLE (-4525 2700);
FORCEPROP 1 LAST PART_NUMBER CS03322FB03
J 0
(-4600 2600);
DISPLAY 0.404255 (-4600 2600);
DISPLAY INVISIBLE (-4600 2600);
FORCEADD OFFPAGE..1
(-8625 5275);
FORCEPROP 2 LAST $XR0 251 
J 0
(-8877 5275);
DISPLAY 0.638298 (-8877 5275);
PAINT MONO (-8877 5275);
FORCEPROP 2 LAST CDS_LIB standard
J 0
(-8625 5275);
PAINT MONO (-8625 5275);
DISPLAY INVISIBLE (-8625 5275);
FORCEPROP 1 LAST OFFPAGE TRUE
J 0
(-8300 5150);
DISPLAY 0.872340 (-8300 5150);
DISPLAY INVISIBLE (-8300 5150);
FORCEPROP 1 LAST COMMENT_BODY TRUE
J 0
(-8500 5175);
DISPLAY 0.872340 (-8500 5175);
PAINT GREEN (-8500 5175);
DISPLAY INVISIBLE (-8500 5175);
FORCEPROP 2 LAST PATH I4
J 0
(-8900 5325);
DISPLAY 0.680851 (-8900 5325);
DISPLAY INVISIBLE (-8900 5325);
FORCEADD UNIVERSAL_POWER..1
(-5025 3300);
FORCEPROP 3 LASTPIN (-5025 3250) SIG_NAME P3V3_AUX\g
J 0
(-5015 3260);
DISPLAY 0.659574 (-5015 3260);
PAINT MONO (-5015 3260);
DISPLAY INVISIBLE (-5015 3260);
FORCEPROP 1 LAST HDL_POWER P3V3_AUX
J 1
(-5025 3350);
DISPLAY 0.872340 (-5025 3350);
PAINT GREEN (-5025 3350);
FORCEPROP 2 LAST CDS_LIB pure_quanta_power
J 0
(-5025 3300);
PAINT MONO (-5025 3300);
DISPLAY INVISIBLE (-5025 3300);
FORCEPROP 1 LAST PATH I40
J 0
(-4975 3325);
DISPLAY 0.872340 (-4975 3325);
PAINT AQUA (-4975 3325);
DISPLAY INVISIBLE (-4975 3325);
FORCEADD UNIVERSAL_GND..1
(-4375 3675);
FORCEPROP 3 LASTPIN (-4375 3725) SIG_NAME GND\g
J 0
(-4365 3735);
DISPLAY 0.659574 (-4365 3735);
PAINT MONO (-4365 3735);
DISPLAY INVISIBLE (-4365 3735);
FORCEPROP 2 LAST CDS_LIB pure_quanta_power
J 0
(-4375 3675);
PAINT MONO (-4375 3675);
DISPLAY INVISIBLE (-4375 3675);
FORCEPROP 1 LAST HDL_POWER GND
J 1
(-4350 3600);
DISPLAY 0.872340 (-4350 3600);
PAINT GREEN (-4350 3600);
DISPLAY INVISIBLE (-4350 3600);
FORCEPROP 1 LAST PATH I41
J 0
(-4300 3675);
DISPLAY 0.872340 (-4300 3675);
PAINT AQUA (-4300 3675);
DISPLAY INVISIBLE (-4300 3675);
FORCEADD LTC4307CMS8..1
(-3900 3950);
FORCEPROP 1 LAST LOCATION U194
J 0
(-4150 4255);
DISPLAY 0.723404 (-4150 4255);
PAINT GREEN (-4150 4255);
FORCEPROP 0 LAST $SEC 1
J 0
(-4150 4400);
DISPLAY 0.680851 (-4150 4400);
PAINT MONO (-4150 4400);
DISPLAY INVISIBLE (-4150 4400);
FORCEPROP 0 LAST CDS_SEC 1
J 0
(-4150 4400);
DISPLAY 1.021277 (-4150 4400);
DISPLAY INVISIBLE (-4150 4400);
FORCEPROP 0 LASTPIN (-4300 4100) $PN 1
J 2
(-4310 4110);
DISPLAY 0.680851 (-4310 4110);
PAINT MONO (-4310 4110);
FORCEPROP 0 LASTPIN (-4300 3800) $PN 4
J 2
(-4310 3810);
DISPLAY 0.680851 (-4310 3810);
PAINT MONO (-4310 3810);
FORCEPROP 0 LASTPIN (-3500 3800) $PN 5
J 0
(-3490 3810);
DISPLAY 0.680851 (-3490 3810);
PAINT MONO (-3490 3810);
FORCEPROP 0 LASTPIN (-4300 4000) $PN 3
J 2
(-4310 4010);
DISPLAY 0.680851 (-4310 4010);
PAINT MONO (-4310 4010);
FORCEPROP 0 LASTPIN (-3500 4000) $PN 2
J 0
(-3490 4010);
DISPLAY 0.680851 (-3490 4010);
PAINT MONO (-3490 4010);
FORCEPROP 0 LASTPIN (-4300 3900) $PN 6
J 2
(-4310 3910);
DISPLAY 0.680851 (-4310 3910);
PAINT MONO (-4310 3910);
FORCEPROP 0 LASTPIN (-3500 3900) $PN 7
J 0
(-3490 3910);
DISPLAY 0.680851 (-3490 3910);
PAINT MONO (-3490 3910);
FORCEPROP 0 LASTPIN (-3500 4100) $PN 8
J 0
(-3490 4110);
DISPLAY 0.680851 (-3490 4110);
PAINT MONO (-3490 4110);
FORCEPROP 2 LAST PART_TYPE SMLF
J 0
(-4150 4350);
DISPLAY 1.021277 (-4150 4350);
FORCEPROP 1 LAST MATERIAL IC
J 0
(-4150 4160);
DISPLAY 0.723404 (-4150 4160);
PAINT GREEN (-4150 4160);
FORCEPROP 2 LAST VALUE LTC4307CMS8
J 0
(-4150 4300);
DISPLAY 1.021277 (-4150 4300);
FORCEPROP 2 LAST CDS_LIB pure_quanta
J 0
(-3900 3950);
DISPLAY INVISIBLE (-3900 3950);
FORCEPROP 1 LAST NEEDS_NO_SIZE TRUE
J 0
(-3900 3950);
DISPLAY 0.468085 (-3900 3950);
PAINT GREEN (-3900 3950);
DISPLAY INVISIBLE (-3900 3950);
FORCEPROP 1 LAST PATH I42
J 0
(-3675 4155);
DISPLAY 0.723404 (-3675 4155);
PAINT GREEN (-3675 4155);
DISPLAY INVISIBLE (-3675 4155);
FORCEPROP 1 LAST PART_NUMBER AL004307000
J 0
(-4150 4210);
DISPLAY 0.723404 (-4150 4210);
PAINT GREEN (-4150 4210);
DISPLAY INVISIBLE (-4150 4210);
FORCEADD Q_RES..1
(-7775 5275);
FORCEPROP 1 LAST LOCATION R3106
J 0
(-7950 5250);
DISPLAY 0.510638 (-7950 5250);
FORCEPROP 0 LAST $SEC 1
J 0
(-7900 5325);
DISPLAY 0.680851 (-7900 5325);
PAINT MONO (-7900 5325);
DISPLAY INVISIBLE (-7900 5325);
FORCEPROP 0 LAST CDS_SEC 1
J 0
(-7900 5325);
DISPLAY 1.021277 (-7900 5325);
DISPLAY INVISIBLE (-7900 5325);
FORCEPROP 1 LASTPIN (-7875 5275) $PN 1
J 0
(-7863 5287);
DISPLAY 0.787234 (-7863 5287);
PAINT MONO (-7863 5287);
FORCEPROP 1 LASTPIN (-7675 5275) $PN 2
J 0
(-7713 5287);
DISPLAY 0.787234 (-7713 5287);
PAINT MONO (-7713 5287);
FORCEPROP 1 LAST VALUE 0
J 2
(-7625 5275);
DISPLAY 0.510638 (-7625 5275);
FORCEPROP 1 LAST TOLERANCE 5%
J 0
(-7575 5275);
DISPLAY 0.510638 (-7575 5275);
FORCEPROP 1 LAST MATERIAL CHIP
J 0
(-7525 5275);
DISPLAY 0.510638 (-7525 5275);
FORCEPROP 1 LAST PACK_TYPE 0402LF
J 0
(-7850 5225);
DISPLAY 0.404255 (-7850 5225);
FORCEPROP 1 LAST WATTAGE 1/16W
J 2
(-7625 5225);
DISPLAY 0.404255 (-7625 5225);
FORCEPROP 2 LAST CDS_LIB pure_quanta
J 0
(-7775 5275);
DISPLAY INVISIBLE (-7775 5275);
FORCEPROP 1 LAST PATH I43
J 0
(-7825 5425);
DISPLAY 0.978723 (-7825 5425);
PAINT WHITE (-7825 5425);
DISPLAY INVISIBLE (-7825 5425);
FORCEPROP 1 LAST PART_NUMBER CS00002JB13
J 0
(-7850 5175);
DISPLAY 0.404255 (-7850 5175);
DISPLAY INVISIBLE (-7850 5175);
FORCEADD Q_RES..1
(-7775 5375);
FORCEPROP 1 LAST LOCATION R3105
J 0
(-7950 5350);
DISPLAY 0.510638 (-7950 5350);
FORCEPROP 0 LAST $SEC 1
J 0
(-7900 5425);
DISPLAY 0.680851 (-7900 5425);
PAINT MONO (-7900 5425);
DISPLAY INVISIBLE (-7900 5425);
FORCEPROP 0 LAST CDS_SEC 1
J 0
(-7900 5425);
DISPLAY 1.021277 (-7900 5425);
DISPLAY INVISIBLE (-7900 5425);
FORCEPROP 1 LASTPIN (-7875 5375) $PN 1
J 0
(-7863 5387);
DISPLAY 0.787234 (-7863 5387);
PAINT MONO (-7863 5387);
FORCEPROP 1 LASTPIN (-7675 5375) $PN 2
J 0
(-7713 5387);
DISPLAY 0.787234 (-7713 5387);
PAINT MONO (-7713 5387);
FORCEPROP 1 LAST VALUE 0
J 2
(-7625 5375);
DISPLAY 0.510638 (-7625 5375);
FORCEPROP 1 LAST TOLERANCE 5%
J 0
(-7575 5375);
DISPLAY 0.510638 (-7575 5375);
FORCEPROP 1 LAST MATERIAL CHIP
J 0
(-7525 5375);
DISPLAY 0.510638 (-7525 5375);
FORCEPROP 2 LAST CDS_LIB pure_quanta
J 0
(-7775 5375);
DISPLAY INVISIBLE (-7775 5375);
FORCEPROP 1 LAST WATTAGE 1/16W
J 2
(-7625 5325);
DISPLAY 0.404255 (-7625 5325);
DISPLAY INVISIBLE (-7625 5325);
FORCEPROP 1 LAST PACK_TYPE 0402LF
J 0
(-7925 5325);
DISPLAY 0.404255 (-7925 5325);
DISPLAY INVISIBLE (-7925 5325);
FORCEPROP 1 LAST PATH I44
J 0
(-7825 5525);
DISPLAY 0.978723 (-7825 5525);
PAINT WHITE (-7825 5525);
DISPLAY INVISIBLE (-7825 5525);
FORCEPROP 1 LAST PART_NUMBER CS00002JB13
J 0
(-7800 5300);
DISPLAY 0.404255 (-7800 5300);
DISPLAY INVISIBLE (-7800 5300);
FORCEADD Q_RES..1
(-7775 5475);
FORCEPROP 1 LAST LOCATION R2707
J 0
(-8000 5475);
DISPLAY 0.638298 (-8000 5475);
FORCEPROP 0 LAST $SEC 1
J 0
(-7650 5575);
DISPLAY 0.680851 (-7650 5575);
PAINT MONO (-7650 5575);
DISPLAY INVISIBLE (-7650 5575);
FORCEPROP 0 LAST CDS_SEC 1
J 0
(-7650 5575);
DISPLAY 1.021277 (-7650 5575);
DISPLAY INVISIBLE (-7650 5575);
FORCEPROP 1 LASTPIN (-7875 5475) $PN 1
J 0
(-7863 5487);
DISPLAY 0.787234 (-7863 5487);
PAINT MONO (-7863 5487);
FORCEPROP 1 LASTPIN (-7675 5475) $PN 2
J 0
(-7713 5487);
DISPLAY 0.787234 (-7713 5487);
PAINT MONO (-7713 5487);
FORCEPROP 1 LAST MATERIAL CHIP
J 0
(-7525 5475);
DISPLAY 0.510638 (-7525 5475);
FORCEPROP 1 LAST VALUE 0
J 2
(-7625 5475);
DISPLAY 0.510638 (-7625 5475);
FORCEPROP 1 LAST TOLERANCE 5%
J 0
(-7575 5475);
DISPLAY 0.510638 (-7575 5475);
FORCEPROP 2 LAST CDS_LIB pure_quanta
J 0
(-7775 5475);
DISPLAY INVISIBLE (-7775 5475);
FORCEPROP 1 LAST PACK_TYPE 0402LF
J 0
(-7925 5425);
DISPLAY 0.404255 (-7925 5425);
DISPLAY INVISIBLE (-7925 5425);
FORCEPROP 1 LAST WATTAGE 1/16W
J 2
(-7625 5425);
DISPLAY 0.404255 (-7625 5425);
DISPLAY INVISIBLE (-7625 5425);
FORCEPROP 1 LAST PATH I45
J 0
(-7825 5625);
DISPLAY 0.978723 (-7825 5625);
PAINT WHITE (-7825 5625);
DISPLAY INVISIBLE (-7825 5625);
FORCEPROP 1 LAST PART_NUMBER CS00002JB13
J 0
(-7875 5550);
DISPLAY 0.404255 (-7875 5550);
DISPLAY INVISIBLE (-7875 5550);
FORCEADD UNIVERSAL_GND..1
(-6675 5050);
FORCEPROP 3 LASTPIN (-6675 5100) SIG_NAME GND\g
J 0
(-6665 5110);
DISPLAY 0.659574 (-6665 5110);
PAINT MONO (-6665 5110);
DISPLAY INVISIBLE (-6665 5110);
FORCEPROP 2 LAST CDS_LIB pure_quanta_power
J 0
(-6675 5050);
PAINT MONO (-6675 5050);
DISPLAY INVISIBLE (-6675 5050);
FORCEPROP 1 LAST HDL_POWER GND
J 1
(-6650 4975);
DISPLAY 0.872340 (-6650 4975);
PAINT GREEN (-6650 4975);
DISPLAY INVISIBLE (-6650 4975);
FORCEPROP 1 LAST PATH I46
J 0
(-6600 5050);
DISPLAY 0.872340 (-6600 5050);
PAINT AQUA (-6600 5050);
DISPLAY INVISIBLE (-6600 5050);
FORCEADD Q_RES..1
(-6300 4925);
FORCEPROP 1 LAST LOCATION R2705
J 0
(-6475 4925);
DISPLAY 0.638298 (-6475 4925);
FORCEPROP 0 LAST $SEC 1
J 0
(-6175 5025);
DISPLAY 0.680851 (-6175 5025);
PAINT MONO (-6175 5025);
DISPLAY INVISIBLE (-6175 5025);
FORCEPROP 0 LAST CDS_SEC 1
J 0
(-6175 5025);
DISPLAY 1.021277 (-6175 5025);
DISPLAY INVISIBLE (-6175 5025);
FORCEPROP 1 LASTPIN (-6400 4925) $PN 1
J 0
(-6388 4937);
DISPLAY 0.787234 (-6388 4937);
PAINT MONO (-6388 4937);
FORCEPROP 1 LASTPIN (-6200 4925) $PN 2
J 0
(-6238 4937);
DISPLAY 0.787234 (-6238 4937);
PAINT MONO (-6238 4937);
FORCEPROP 1 LAST MATERIAL EMPTY
J 0
(-6000 4925);
DISPLAY 0.510638 (-6000 4925);
PAINT RED (-6000 4925);
FORCEPROP 1 LAST VALUE 0
J 2
(-6150 4925);
DISPLAY 0.510638 (-6150 4925);
FORCEPROP 2 LAST CDS_LIB pure_quanta
J 0
(-6300 4925);
DISPLAY INVISIBLE (-6300 4925);
FORCEPROP 1 LAST PACK_TYPE 0402LF
J 0
(-6400 4825);
DISPLAY 0.404255 (-6400 4825);
DISPLAY INVISIBLE (-6400 4825);
FORCEPROP 1 LAST TOLERANCE 5%
J 0
(-6075 4925);
DISPLAY 0.510638 (-6075 4925);
DISPLAY INVISIBLE (-6075 4925);
FORCEPROP 1 LAST WATTAGE 1/16W
J 2
(-6175 4825);
DISPLAY 0.404255 (-6175 4825);
DISPLAY INVISIBLE (-6175 4825);
FORCEPROP 1 LAST PATH I47
J 0
(-6350 5075);
DISPLAY 0.978723 (-6350 5075);
PAINT WHITE (-6350 5075);
DISPLAY INVISIBLE (-6350 5075);
FORCEPROP 1 LAST PART_NUMBER CS00002JB13
J 0
(-6400 4875);
DISPLAY 0.404255 (-6400 4875);
DISPLAY INVISIBLE (-6400 4875);
FORCEADD Q_RES..1
(-6300 4850);
FORCEPROP 1 LAST LOCATION R2724
J 0
(-6475 4850);
DISPLAY 0.638298 (-6475 4850);
FORCEPROP 2 LAST $SEC 1
J 0
(-6350 5050);
DISPLAY 0.680851 (-6350 5050);
PAINT MONO (-6350 5050);
DISPLAY INVISIBLE (-6350 5050);
FORCEPROP 2 LAST CDS_SEC 1
J 0
(-6350 5050);
DISPLAY 1.021277 (-6350 5050);
DISPLAY INVISIBLE (-6350 5050);
FORCEPROP 1 LASTPIN (-6400 4850) $PN 1
J 0
(-6388 4862);
DISPLAY 0.787234 (-6388 4862);
PAINT MONO (-6388 4862);
FORCEPROP 1 LASTPIN (-6200 4850) $PN 2
J 0
(-6238 4862);
DISPLAY 0.787234 (-6238 4862);
PAINT MONO (-6238 4862);
FORCEPROP 1 LAST TOLERANCE 5%
J 0
(-6075 4850);
DISPLAY 0.510638 (-6075 4850);
FORCEPROP 1 LAST PACK_TYPE 0402LF
J 0
(-6400 4750);
DISPLAY 0.404255 (-6400 4750);
FORCEPROP 1 LAST WATTAGE 1/16W
J 2
(-6175 4750);
DISPLAY 0.404255 (-6175 4750);
FORCEPROP 1 LAST VALUE 0
J 2
(-6150 4850);
DISPLAY 0.510638 (-6150 4850);
FORCEPROP 1 LAST MATERIAL EMPTY
J 0
(-6000 4850);
DISPLAY 0.510638 (-6000 4850);
PAINT RED (-6000 4850);
FORCEPROP 2 LAST CDS_LIB pure_quanta
J 0
(-6300 4850);
DISPLAY INVISIBLE (-6300 4850);
FORCEPROP 1 LAST PATH I48
J 0
(-6350 5000);
DISPLAY 0.978723 (-6350 5000);
PAINT WHITE (-6350 5000);
DISPLAY INVISIBLE (-6350 5000);
FORCEPROP 1 LAST PART_NUMBER CS00002JB13
J 0
(-6400 4800);
DISPLAY 0.404255 (-6400 4800);
DISPLAY INVISIBLE (-6400 4800);
FORCEADD LTC4307CMS8..1
(-6275 5325);
FORCEPROP 1 LAST LOCATION U175
J 0
(-6525 5630);
DISPLAY 0.723404 (-6525 5630);
PAINT GREEN (-6525 5630);
FORCEPROP 0 LAST $SEC 1
J 0
(-6525 5775);
DISPLAY 0.680851 (-6525 5775);
PAINT MONO (-6525 5775);
DISPLAY INVISIBLE (-6525 5775);
FORCEPROP 0 LAST CDS_SEC 1
J 0
(-6525 5775);
DISPLAY 1.021277 (-6525 5775);
DISPLAY INVISIBLE (-6525 5775);
FORCEPROP 0 LASTPIN (-6675 5475) $PN 1
J 2
(-6685 5485);
DISPLAY 0.680851 (-6685 5485);
PAINT MONO (-6685 5485);
FORCEPROP 0 LASTPIN (-6675 5175) $PN 4
J 2
(-6685 5185);
DISPLAY 0.680851 (-6685 5185);
PAINT MONO (-6685 5185);
FORCEPROP 0 LASTPIN (-5875 5175) $PN 5
J 0
(-5865 5185);
DISPLAY 0.680851 (-5865 5185);
PAINT MONO (-5865 5185);
FORCEPROP 0 LASTPIN (-6675 5375) $PN 3
J 2
(-6685 5385);
DISPLAY 0.680851 (-6685 5385);
PAINT MONO (-6685 5385);
FORCEPROP 0 LASTPIN (-5875 5375) $PN 2
J 0
(-5865 5385);
DISPLAY 0.680851 (-5865 5385);
PAINT MONO (-5865 5385);
FORCEPROP 0 LASTPIN (-6675 5275) $PN 6
J 2
(-6685 5285);
DISPLAY 0.680851 (-6685 5285);
PAINT MONO (-6685 5285);
FORCEPROP 0 LASTPIN (-5875 5275) $PN 7
J 0
(-5865 5285);
DISPLAY 0.680851 (-5865 5285);
PAINT MONO (-5865 5285);
FORCEPROP 0 LASTPIN (-5875 5475) $PN 8
J 0
(-5865 5485);
DISPLAY 0.680851 (-5865 5485);
PAINT MONO (-5865 5485);
FORCEPROP 1 LAST MATERIAL IC
J 0
(-6525 5535);
DISPLAY 0.723404 (-6525 5535);
PAINT GREEN (-6525 5535);
FORCEPROP 2 LAST PART_TYPE SMLF
J 0
(-6525 5725);
DISPLAY 1.021277 (-6525 5725);
FORCEPROP 2 LAST VALUE LTC4307CMS8
J 0
(-6525 5675);
DISPLAY 1.021277 (-6525 5675);
FORCEPROP 1 LAST NEEDS_NO_SIZE TRUE
J 0
(-6275 5325);
DISPLAY 0.468085 (-6275 5325);
PAINT GREEN (-6275 5325);
DISPLAY INVISIBLE (-6275 5325);
FORCEPROP 2 LAST CDS_LIB pure_quanta
J 0
(-6275 5325);
DISPLAY INVISIBLE (-6275 5325);
FORCEPROP 1 LAST PATH I49
J 0
(-6050 5530);
DISPLAY 0.723404 (-6050 5530);
PAINT GREEN (-6050 5530);
DISPLAY INVISIBLE (-6050 5530);
FORCEPROP 1 LAST PART_NUMBER AL004307000
J 0
(-6525 5585);
DISPLAY 0.723404 (-6525 5585);
PAINT GREEN (-6525 5585);
DISPLAY INVISIBLE (-6525 5585);
FORCEADD OFFPAGE..6
(-8625 5375);
FORCEPROP 2 LAST $XR0 251 
J 0
(-8935 5375);
DISPLAY 0.638298 (-8935 5375);
PAINT MONO (-8935 5375);
FORCEPROP 2 LAST CDS_LIB standard
J 0
(-8625 5375);
PAINT MONO (-8625 5375);
DISPLAY INVISIBLE (-8625 5375);
FORCEPROP 1 LAST OFFPAGE TRUE
J 0
(-8300 5250);
DISPLAY 0.872340 (-8300 5250);
DISPLAY INVISIBLE (-8300 5250);
FORCEPROP 1 LAST COMMENT_BODY TRUE
J 0
(-8525 5300);
DISPLAY 0.872340 (-8525 5300);
PAINT GREEN (-8525 5300);
DISPLAY INVISIBLE (-8525 5300);
FORCEPROP 2 LAST PATH I5
J 0
(-8925 5425);
DISPLAY 0.680851 (-8925 5425);
DISPLAY INVISIBLE (-8925 5425);
FORCEADD Q_RES..1
(-5750 4100);
FORCEPROP 1 LAST LOCATION R2899
J 0
(-5975 4100);
DISPLAY 0.638298 (-5975 4100);
FORCEPROP 0 LAST $SEC 1
J 0
(-5625 4200);
DISPLAY 0.680851 (-5625 4200);
PAINT MONO (-5625 4200);
DISPLAY INVISIBLE (-5625 4200);
FORCEPROP 0 LAST CDS_SEC 1
J 0
(-5625 4200);
DISPLAY 1.021277 (-5625 4200);
DISPLAY INVISIBLE (-5625 4200);
FORCEPROP 1 LASTPIN (-5850 4100) $PN 1
J 0
(-5838 4112);
DISPLAY 0.787234 (-5838 4112);
PAINT MONO (-5838 4112);
FORCEPROP 1 LASTPIN (-5650 4100) $PN 2
J 0
(-5688 4112);
DISPLAY 0.787234 (-5688 4112);
PAINT MONO (-5688 4112);
FORCEPROP 1 LAST VALUE 0
J 2
(-5600 4100);
DISPLAY 0.510638 (-5600 4100);
FORCEPROP 1 LAST MATERIAL CHIP
J 0
(-5500 4100);
DISPLAY 0.510638 (-5500 4100);
FORCEPROP 1 LAST TOLERANCE 5%
J 0
(-5550 4100);
DISPLAY 0.510638 (-5550 4100);
FORCEPROP 1 LAST WATTAGE 1/16W
J 2
(-5625 4000);
DISPLAY 0.404255 (-5625 4000);
DISPLAY INVISIBLE (-5625 4000);
FORCEPROP 1 LAST PACK_TYPE 0402LF
J 0
(-5850 4000);
DISPLAY 0.404255 (-5850 4000);
DISPLAY INVISIBLE (-5850 4000);
FORCEPROP 2 LAST CDS_LIB pure_quanta
J 0
(-5750 4100);
DISPLAY INVISIBLE (-5750 4100);
FORCEPROP 1 LAST PATH I50
J 0
(-5800 4250);
DISPLAY 0.978723 (-5800 4250);
PAINT WHITE (-5800 4250);
DISPLAY INVISIBLE (-5800 4250);
FORCEPROP 1 LAST PART_NUMBER CS00002JB13
J 0
(-5850 4050);
DISPLAY 0.404255 (-5850 4050);
DISPLAY INVISIBLE (-5850 4050);
FORCEADD UNIVERSAL_GND..1
(-5650 5500);
FORCEPROP 3 LASTPIN (-5650 5550) SIG_NAME GND\g
J 0
(-5640 5560);
DISPLAY 0.659574 (-5640 5560);
PAINT MONO (-5640 5560);
DISPLAY INVISIBLE (-5640 5560);
FORCEPROP 2 LAST CDS_LIB pure_quanta_power
J 0
(-5650 5500);
PAINT MONO (-5650 5500);
DISPLAY INVISIBLE (-5650 5500);
FORCEPROP 1 LAST HDL_POWER GND
J 1
(-5625 5425);
DISPLAY 0.872340 (-5625 5425);
PAINT GREEN (-5625 5425);
DISPLAY INVISIBLE (-5625 5425);
FORCEPROP 1 LAST PATH I51
J 0
(-5575 5500);
DISPLAY 0.872340 (-5575 5500);
PAINT AQUA (-5575 5500);
DISPLAY INVISIBLE (-5575 5500);
FORCEADD Q_CAP..1
(-5650 5725);
FORCEPROP 1 LAST LOCATION C1707
J 0
(-5600 5825);
DISPLAY 0.978723 (-5600 5825);
FORCEPROP 2 LAST $SEC 1
J 0
(-5600 5925);
DISPLAY 0.680851 (-5600 5925);
PAINT MONO (-5600 5925);
DISPLAY INVISIBLE (-5600 5925);
FORCEPROP 2 LAST CDS_SEC 1
J 0
(-5600 5925);
DISPLAY 1.021277 (-5600 5925);
DISPLAY INVISIBLE (-5600 5925);
FORCEPROP 1 LASTPIN (-5650 5825) $PN 1
J 0
(-5640 5805);
DISPLAY 0.787234 (-5640 5805);
FORCEPROP 1 LASTPIN (-5650 5625) $PN 2
J 0
(-5640 5605);
DISPLAY 0.787234 (-5640 5605);
FORCEPROP 1 LAST PACK_TYPE 0402
J 0
(-5600 5525);
DISPLAY 0.510638 (-5600 5525);
FORCEPROP 1 LAST MATERIAL X7R
J 0
(-5600 5625);
DISPLAY 0.510638 (-5600 5625);
FORCEPROP 1 LAST TOLERANCE 10%
J 0
(-5600 5675);
DISPLAY 0.510638 (-5600 5675);
FORCEPROP 1 LAST VOLTAGE 25V
J 0
(-5600 5725);
DISPLAY 0.510638 (-5600 5725);
FORCEPROP 1 LAST VALUE 0.1UF
J 0
(-5600 5775);
DISPLAY 0.510638 (-5600 5775);
FORCEPROP 2 LAST CDS_LIB pure_quanta
J 0
(-5650 5725);
PAINT MONO (-5650 5725);
DISPLAY INVISIBLE (-5650 5725);
FORCEPROP 1 LAST PATH I52
J 0
(-5600 5875);
DISPLAY 0.978723 (-5600 5875);
PAINT WHITE (-5600 5875);
DISPLAY INVISIBLE (-5600 5875);
FORCEPROP 1 LAST PART_NUMBER CH4104K1B00
J 0
(-5600 5575);
DISPLAY 0.510638 (-5600 5575);
DISPLAY INVISIBLE (-5600 5575);
FORCEADD UNIVERSAL_POWER..1
(-5825 6025);
FORCEPROP 3 LASTPIN (-5825 5975) SIG_NAME P3V3_AUX\g
J 0
(-5815 5985);
DISPLAY 0.659574 (-5815 5985);
PAINT MONO (-5815 5985);
DISPLAY INVISIBLE (-5815 5985);
FORCEPROP 1 LAST HDL_POWER P3V3_AUX
J 1
(-5825 6075);
DISPLAY 0.872340 (-5825 6075);
PAINT GREEN (-5825 6075);
FORCEPROP 2 LAST CDS_LIB pure_quanta_power
J 0
(-5825 6025);
PAINT MONO (-5825 6025);
DISPLAY INVISIBLE (-5825 6025);
FORCEPROP 1 LAST PATH I53
J 0
(-5775 6050);
DISPLAY 0.872340 (-5775 6050);
PAINT AQUA (-5775 6050);
DISPLAY INVISIBLE (-5775 6050);
FORCEADD Q_RES..2
(-4800 5700);
FORCEPROP 1 LAST LOCATION R2667
J 0
(-4755 5825);
DISPLAY 0.404255 (-4755 5825);
FORCEPROP 0 LAST $SEC 1
J 0
(-4750 5850);
DISPLAY 0.680851 (-4750 5850);
PAINT MONO (-4750 5850);
DISPLAY INVISIBLE (-4750 5850);
FORCEPROP 2 LAST CDS_SEC 1
J 0
(-4750 5925);
DISPLAY 1.021277 (-4750 5925);
DISPLAY INVISIBLE (-4750 5925);
FORCEPROP 1 LASTPIN (-4800 5800) $PN 1
J 0
(-4795 5762);
DISPLAY 0.787234 (-4795 5762);
PAINT MONO (-4795 5762);
FORCEPROP 1 LASTPIN (-4800 5600) $PN 2
J 0
(-4795 5610);
DISPLAY 0.787234 (-4795 5610);
PAINT MONO (-4795 5610);
FORCEPROP 1 LAST VALUE 2.2K
J 0
(-4755 5775);
DISPLAY 0.404255 (-4755 5775);
FORCEPROP 1 LAST PACK_TYPE 0402LF
J 0
(-4760 5525);
DISPLAY 0.404255 (-4760 5525);
FORCEPROP 1 LAST TOLERANCE 5%
J 0
(-4755 5725);
DISPLAY 0.404255 (-4755 5725);
FORCEPROP 1 LAST MATERIAL CHIP
J 0
(-4760 5625);
DISPLAY 0.404255 (-4760 5625);
FORCEPROP 1 LAST WATTAGE 1/16W
J 0
(-4760 5675);
DISPLAY 0.404255 (-4760 5675);
FORCEPROP 2 LAST CDS_LIB pure_quanta
J 0
(-4800 5700);
DISPLAY INVISIBLE (-4800 5700);
FORCEPROP 1 LAST PATH I54
J 0
(-4750 5875);
DISPLAY 0.978723 (-4750 5875);
PAINT WHITE (-4750 5875);
DISPLAY INVISIBLE (-4750 5875);
FORCEPROP 1 LAST PART_NUMBER CS22202JB07
J 0
(-4760 5575);
DISPLAY 0.404255 (-4760 5575);
DISPLAY INVISIBLE (-4760 5575);
FORCEADD UNIVERSAL_POWER..1
(-4800 6025);
FORCEPROP 3 LASTPIN (-4800 5975) SIG_NAME P3V3_AUX\g
J 0
(-4790 5985);
DISPLAY 0.659574 (-4790 5985);
PAINT MONO (-4790 5985);
DISPLAY INVISIBLE (-4790 5985);
FORCEPROP 1 LAST HDL_POWER P3V3_AUX
J 1
(-4800 6075);
DISPLAY 0.872340 (-4800 6075);
PAINT GREEN (-4800 6075);
FORCEPROP 2 LAST CDS_LIB pure_quanta_power
J 0
(-4800 6025);
PAINT MONO (-4800 6025);
DISPLAY INVISIBLE (-4800 6025);
FORCEPROP 1 LAST PATH I55
J 0
(-4750 6050);
DISPLAY 0.872340 (-4750 6050);
PAINT AQUA (-4750 6050);
DISPLAY INVISIBLE (-4750 6050);
FORCEADD Q_RES..1
(-4250 5275);
FORCEPROP 1 LAST LOCATION R2672
J 0
(-4475 5275);
DISPLAY 0.638298 (-4475 5275);
FORCEPROP 0 LAST $SEC 1
J 0
(-4475 5325);
DISPLAY 0.680851 (-4475 5325);
PAINT MONO (-4475 5325);
DISPLAY INVISIBLE (-4475 5325);
FORCEPROP 0 LAST CDS_SEC 1
J 0
(-4475 5325);
DISPLAY 1.021277 (-4475 5325);
DISPLAY INVISIBLE (-4475 5325);
FORCEPROP 1 LASTPIN (-4350 5275) $PN 1
J 0
(-4338 5287);
DISPLAY 0.787234 (-4338 5287);
PAINT MONO (-4338 5287);
FORCEPROP 1 LASTPIN (-4150 5275) $PN 2
J 0
(-4188 5287);
DISPLAY 0.787234 (-4188 5287);
PAINT MONO (-4188 5287);
FORCEPROP 1 LAST MATERIAL CHIP
J 0
(-3950 5275);
DISPLAY 0.510638 (-3950 5275);
FORCEPROP 1 LAST VALUE 33.2
J 2
(-4050 5275);
DISPLAY 0.510638 (-4050 5275);
FORCEPROP 1 LAST TOLERANCE 1%
J 0
(-4025 5275);
DISPLAY 0.510638 (-4025 5275);
FORCEPROP 1 LAST WATTAGE 1/16W
J 2
(-4150 5375);
DISPLAY 0.404255 (-4150 5375);
DISPLAY INVISIBLE (-4150 5375);
FORCEPROP 1 LAST PACK_TYPE 0402LF
J 0
(-4375 5375);
DISPLAY 0.404255 (-4375 5375);
DISPLAY INVISIBLE (-4375 5375);
FORCEPROP 2 LAST CDS_LIB pure_quanta
J 0
(-4250 5275);
DISPLAY INVISIBLE (-4250 5275);
FORCEPROP 1 LAST PATH I56
J 0
(-4300 5425);
DISPLAY 0.978723 (-4300 5425);
PAINT WHITE (-4300 5425);
DISPLAY INVISIBLE (-4300 5425);
FORCEPROP 1 LAST PART_NUMBER CS03322FB03
J 0
(-4375 5325);
DISPLAY 0.404255 (-4375 5325);
DISPLAY INVISIBLE (-4375 5325);
FORCEADD Q_RES..2
(-4550 5700);
FORCEPROP 1 LAST LOCATION R2669
J 0
(-4505 5825);
DISPLAY 0.404255 (-4505 5825);
FORCEPROP 0 LAST $SEC 1
J 0
(-4500 5850);
DISPLAY 0.680851 (-4500 5850);
PAINT MONO (-4500 5850);
DISPLAY INVISIBLE (-4500 5850);
FORCEPROP 2 LAST CDS_SEC 1
J 0
(-4500 5925);
DISPLAY 1.021277 (-4500 5925);
DISPLAY INVISIBLE (-4500 5925);
FORCEPROP 1 LASTPIN (-4550 5800) $PN 1
J 0
(-4545 5762);
DISPLAY 0.787234 (-4545 5762);
PAINT MONO (-4545 5762);
FORCEPROP 1 LASTPIN (-4550 5600) $PN 2
J 0
(-4545 5610);
DISPLAY 0.787234 (-4545 5610);
PAINT MONO (-4545 5610);
FORCEPROP 1 LAST MATERIAL CHIP
J 0
(-4510 5625);
DISPLAY 0.404255 (-4510 5625);
FORCEPROP 1 LAST WATTAGE 1/16W
J 0
(-4510 5675);
DISPLAY 0.404255 (-4510 5675);
FORCEPROP 1 LAST PACK_TYPE 0402LF
J 0
(-4510 5525);
DISPLAY 0.404255 (-4510 5525);
FORCEPROP 1 LAST TOLERANCE 5%
J 0
(-4505 5725);
DISPLAY 0.404255 (-4505 5725);
FORCEPROP 1 LAST VALUE 2.2K
J 0
(-4505 5775);
DISPLAY 0.404255 (-4505 5775);
FORCEPROP 2 LAST CDS_LIB pure_quanta
J 0
(-4550 5700);
DISPLAY INVISIBLE (-4550 5700);
FORCEPROP 1 LAST PATH I57
J 0
(-4500 5875);
DISPLAY 0.978723 (-4500 5875);
PAINT WHITE (-4500 5875);
DISPLAY INVISIBLE (-4500 5875);
FORCEPROP 1 LAST PART_NUMBER CS22202JB07
J 0
(-4510 5575);
DISPLAY 0.404255 (-4510 5575);
DISPLAY INVISIBLE (-4510 5575);
FORCEADD Q_RES..1
(-4250 5375);
FORCEPROP 1 LAST LOCATION R2671
J 0
(-4475 5375);
DISPLAY 0.638298 (-4475 5375);
FORCEPROP 0 LAST $SEC 1
J 0
(-4150 5500);
DISPLAY 0.680851 (-4150 5500);
PAINT MONO (-4150 5500);
DISPLAY INVISIBLE (-4150 5500);
FORCEPROP 0 LAST CDS_SEC 1
J 0
(-4150 5500);
DISPLAY 1.021277 (-4150 5500);
DISPLAY INVISIBLE (-4150 5500);
FORCEPROP 1 LASTPIN (-4350 5375) $PN 1
J 0
(-4338 5387);
DISPLAY 0.787234 (-4338 5387);
PAINT MONO (-4338 5387);
FORCEPROP 1 LASTPIN (-4150 5375) $PN 2
J 0
(-4188 5387);
DISPLAY 0.787234 (-4188 5387);
PAINT MONO (-4188 5387);
FORCEPROP 1 LAST VALUE 33.2
J 2
(-4050 5375);
DISPLAY 0.510638 (-4050 5375);
FORCEPROP 1 LAST PACK_TYPE 0402LF
J 0
(-4375 5475);
DISPLAY 0.404255 (-4375 5475);
FORCEPROP 1 LAST MATERIAL CHIP
J 0
(-3950 5375);
DISPLAY 0.510638 (-3950 5375);
FORCEPROP 1 LAST TOLERANCE 1%
J 0
(-4025 5375);
DISPLAY 0.510638 (-4025 5375);
FORCEPROP 1 LAST WATTAGE 1/16W
J 2
(-4150 5475);
DISPLAY 0.404255 (-4150 5475);
FORCEPROP 2 LAST CDS_LIB pure_quanta
J 0
(-4250 5375);
DISPLAY INVISIBLE (-4250 5375);
FORCEPROP 1 LAST PATH I58
J 0
(-4300 5525);
DISPLAY 0.978723 (-4300 5525);
PAINT WHITE (-4300 5525);
DISPLAY INVISIBLE (-4300 5525);
FORCEPROP 1 LAST PART_NUMBER CS03322FB03
J 0
(-4375 5425);
DISPLAY 0.404255 (-4375 5425);
DISPLAY INVISIBLE (-4375 5425);
FORCEADD UNIVERSAL_GND..1
(-3275 1400);
FORCEPROP 3 LASTPIN (-3275 1450) SIG_NAME GND\g
J 0
(-3265 1460);
DISPLAY 0.659574 (-3265 1460);
PAINT MONO (-3265 1460);
DISPLAY INVISIBLE (-3265 1460);
FORCEPROP 2 LAST CDS_LIB pure_quanta_power
J 0
(-3275 1400);
PAINT MONO (-3275 1400);
DISPLAY INVISIBLE (-3275 1400);
FORCEPROP 1 LAST HDL_POWER GND
J 1
(-3250 1325);
DISPLAY 0.872340 (-3250 1325);
PAINT GREEN (-3250 1325);
DISPLAY INVISIBLE (-3250 1325);
FORCEPROP 1 LAST PATH I59
J 0
(-3200 1400);
DISPLAY 0.872340 (-3200 1400);
PAINT AQUA (-3200 1400);
DISPLAY INVISIBLE (-3200 1400);
FORCEADD OFFPAGE..4
R 2
(-8625 5475);
FORCEPROP 2 LAST $XR1 249 
J 0
(-8966 5475);
DISPLAY 0.638298 (-8966 5475);
PAINT MONO (-8966 5475);
FORCEPROP 2 LAST $XR0 80 
J 0
(-8846 5475);
DISPLAY 0.638298 (-8846 5475);
PAINT MONO (-8846 5475);
FORCEPROP 2 LAST CDS_LIB standard
J 0
(-8625 5475);
DISPLAY INVISIBLE (-8625 5475);
FORCEPROP 1 LAST OFFPAGE TRUE
J 2
(-8950 5350);
DISPLAY 0.872340 (-8950 5350);
DISPLAY INVISIBLE (-8950 5350);
FORCEPROP 1 LAST COMMENT_BODY TRUE
J 2
(-8600 5375);
DISPLAY 0.872340 (-8600 5375);
PAINT GREEN (-8600 5375);
DISPLAY INVISIBLE (-8600 5375);
FORCEPROP 2 LAST PATH I6
J 0
(-8900 5525);
DISPLAY 0.680851 (-8900 5525);
DISPLAY INVISIBLE (-8900 5525);
FORCEADD UNIVERSAL_POWER..1
(-3450 1925);
FORCEPROP 3 LASTPIN (-3450 1875) SIG_NAME P3V3_AUX\g
J 0
(-3440 1885);
DISPLAY 0.659574 (-3440 1885);
PAINT MONO (-3440 1885);
DISPLAY INVISIBLE (-3440 1885);
FORCEPROP 1 LAST HDL_POWER P3V3_AUX
J 1
(-3450 1975);
DISPLAY 0.872340 (-3450 1975);
PAINT GREEN (-3450 1975);
FORCEPROP 2 LAST CDS_LIB pure_quanta_power
J 0
(-3450 1925);
PAINT MONO (-3450 1925);
DISPLAY INVISIBLE (-3450 1925);
FORCEPROP 1 LAST PATH I60
J 0
(-3400 1950);
DISPLAY 0.872340 (-3400 1950);
PAINT AQUA (-3400 1950);
DISPLAY INVISIBLE (-3400 1950);
FORCEADD Q_CAP..1
(-3275 1625);
FORCEPROP 1 LAST LOCATION C1708
J 0
(-3225 1725);
DISPLAY 0.978723 (-3225 1725);
FORCEPROP 2 LAST $SEC 1
J 0
(-3225 1825);
DISPLAY 0.680851 (-3225 1825);
PAINT MONO (-3225 1825);
DISPLAY INVISIBLE (-3225 1825);
FORCEPROP 2 LAST CDS_SEC 1
J 0
(-3225 1825);
DISPLAY 1.021277 (-3225 1825);
DISPLAY INVISIBLE (-3225 1825);
FORCEPROP 1 LASTPIN (-3275 1725) $PN 1
J 0
(-3265 1705);
DISPLAY 0.787234 (-3265 1705);
FORCEPROP 1 LASTPIN (-3275 1525) $PN 2
J 0
(-3265 1505);
DISPLAY 0.787234 (-3265 1505);
FORCEPROP 1 LAST PACK_TYPE 0402
J 0
(-3225 1425);
DISPLAY 0.510638 (-3225 1425);
FORCEPROP 1 LAST MATERIAL X7R
J 0
(-3225 1525);
DISPLAY 0.510638 (-3225 1525);
FORCEPROP 1 LAST TOLERANCE 10%
J 0
(-3225 1575);
DISPLAY 0.510638 (-3225 1575);
FORCEPROP 1 LAST VOLTAGE 25V
J 0
(-3225 1625);
DISPLAY 0.510638 (-3225 1625);
FORCEPROP 1 LAST VALUE 0.1UF
J 0
(-3225 1675);
DISPLAY 0.510638 (-3225 1675);
FORCEPROP 2 LAST CDS_LIB pure_quanta
J 0
(-3275 1625);
PAINT MONO (-3275 1625);
DISPLAY INVISIBLE (-3275 1625);
FORCEPROP 1 LAST PATH I61
J 0
(-3225 1775);
DISPLAY 0.978723 (-3225 1775);
PAINT WHITE (-3225 1775);
DISPLAY INVISIBLE (-3225 1775);
FORCEPROP 1 LAST PART_NUMBER CH4104K1B00
J 0
(-3225 1475);
DISPLAY 0.510638 (-3225 1475);
DISPLAY INVISIBLE (-3225 1475);
FORCEADD Q_RES..2
(-2350 1600);
FORCEPROP 1 LAST LOCATION R2668
J 0
(-2305 1725);
DISPLAY 0.638298 (-2305 1725);
FORCEPROP 2 LAST $SEC 1
J 0
(-2300 1825);
DISPLAY 0.680851 (-2300 1825);
PAINT MONO (-2300 1825);
DISPLAY INVISIBLE (-2300 1825);
FORCEPROP 2 LAST CDS_SEC 1
J 0
(-2300 1825);
DISPLAY 1.021277 (-2300 1825);
DISPLAY INVISIBLE (-2300 1825);
FORCEPROP 1 LASTPIN (-2350 1700) $PN 1
J 0
(-2345 1662);
DISPLAY 0.787234 (-2345 1662);
FORCEPROP 1 LASTPIN (-2350 1500) $PN 2
J 0
(-2345 1510);
DISPLAY 0.787234 (-2345 1510);
FORCEPROP 1 LAST VALUE 4.7K
J 0
(-2305 1675);
DISPLAY 0.638298 (-2305 1675);
FORCEPROP 1 LAST MATERIAL EMPTY
J 0
(-2310 1525);
DISPLAY 0.638298 (-2310 1525);
PAINT RED (-2310 1525);
FORCEPROP 1 LAST WATTAGE 1/16W
J 0
(-2310 1575);
DISPLAY 0.638298 (-2310 1575);
FORCEPROP 1 LAST TOLERANCE 5%
J 0
(-2305 1625);
DISPLAY 0.638298 (-2305 1625);
FORCEPROP 1 LAST PACK_TYPE 0402LF
J 0
(-2310 1475);
DISPLAY 0.638298 (-2310 1475);
FORCEPROP 2 LAST CDS_LIB pure_quanta
J 0
(-2350 1600);
PAINT MONO (-2350 1600);
DISPLAY INVISIBLE (-2350 1600);
FORCEPROP 1 LAST PATH I62
J 0
(-2300 1775);
DISPLAY 0.978723 (-2300 1775);
PAINT WHITE (-2300 1775);
DISPLAY INVISIBLE (-2300 1775);
FORCEPROP 1 LAST PART_NUMBER CS24702JB10
J 0
(-2310 1425);
DISPLAY 0.638298 (-2310 1425);
DISPLAY INVISIBLE (-2310 1425);
FORCEADD Q_RES..2
(-2100 1600);
FORCEPROP 1 LAST LOCATION R2670
J 0
(-2055 1725);
DISPLAY 0.638298 (-2055 1725);
FORCEPROP 2 LAST $SEC 1
J 0
(-2050 1825);
DISPLAY 0.680851 (-2050 1825);
PAINT MONO (-2050 1825);
DISPLAY INVISIBLE (-2050 1825);
FORCEPROP 2 LAST CDS_SEC 1
J 0
(-2050 1825);
DISPLAY 1.021277 (-2050 1825);
DISPLAY INVISIBLE (-2050 1825);
FORCEPROP 1 LASTPIN (-2100 1700) $PN 1
J 0
(-2095 1662);
DISPLAY 0.787234 (-2095 1662);
FORCEPROP 1 LASTPIN (-2100 1500) $PN 2
J 0
(-2095 1510);
DISPLAY 0.787234 (-2095 1510);
FORCEPROP 1 LAST PACK_TYPE 0402LF
J 0
(-2075 1475);
DISPLAY 0.638298 (-2075 1475);
FORCEPROP 1 LAST MATERIAL EMPTY
J 0
(-2060 1525);
DISPLAY 0.638298 (-2060 1525);
PAINT RED (-2060 1525);
FORCEPROP 1 LAST WATTAGE 1/16W
J 0
(-2060 1575);
DISPLAY 0.638298 (-2060 1575);
FORCEPROP 1 LAST VALUE 4.7K
J 0
(-2055 1675);
DISPLAY 0.638298 (-2055 1675);
FORCEPROP 1 LAST TOLERANCE 5%
J 0
(-2055 1625);
DISPLAY 0.638298 (-2055 1625);
FORCEPROP 2 LAST CDS_LIB pure_quanta
J 0
(-2100 1600);
PAINT MONO (-2100 1600);
DISPLAY INVISIBLE (-2100 1600);
FORCEPROP 1 LAST PATH I63
J 0
(-2050 1775);
DISPLAY 0.978723 (-2050 1775);
PAINT WHITE (-2050 1775);
DISPLAY INVISIBLE (-2050 1775);
FORCEPROP 1 LAST PART_NUMBER CS24702JB10
J 0
(-2060 1425);
DISPLAY 0.638298 (-2060 1425);
DISPLAY INVISIBLE (-2060 1425);
FORCEADD UNIVERSAL_POWER..1
(-2350 1925);
FORCEPROP 3 LASTPIN (-2350 1875) SIG_NAME P3V3_AUX\g
J 0
(-2340 1885);
DISPLAY 0.659574 (-2340 1885);
PAINT MONO (-2340 1885);
DISPLAY INVISIBLE (-2340 1885);
FORCEPROP 1 LAST HDL_POWER P3V3_AUX
J 1
(-2350 1975);
DISPLAY 0.872340 (-2350 1975);
PAINT GREEN (-2350 1975);
FORCEPROP 2 LAST CDS_LIB pure_quanta_power
J 0
(-2350 1925);
PAINT MONO (-2350 1925);
DISPLAY INVISIBLE (-2350 1925);
FORCEPROP 1 LAST PATH I64
J 0
(-2300 1950);
DISPLAY 0.872340 (-2300 1950);
PAINT AQUA (-2300 1950);
DISPLAY INVISIBLE (-2300 1950);
FORCEADD OFFPAGE..2
(-3150 2550);
FORCEPROP 2 LAST $XR0 122 
J 0
(-2961 2550);
DISPLAY 0.638298 (-2961 2550);
PAINT MONO (-2961 2550);
FORCEPROP 2 LAST CDS_LIB standard
J 0
(-3150 2550);
DISPLAY INVISIBLE (-3150 2550);
FORCEPROP 1 LAST OFFPAGE TRUE
J 0
(-2825 2425);
DISPLAY 0.872340 (-2825 2425);
PAINT GREEN (-2825 2425);
DISPLAY INVISIBLE (-2825 2425);
FORCEPROP 1 LAST COMMENT_BODY TRUE
J 0
(-3195 2455);
DISPLAY 0.872340 (-3195 2455);
PAINT GREEN (-3195 2455);
DISPLAY INVISIBLE (-3195 2455);
FORCEPROP 2 LAST PATH I65
J 0
(-2975 2625);
DISPLAY 0.680851 (-2975 2625);
DISPLAY INVISIBLE (-2975 2625);
FORCEADD OFFPAGE..3
(-3150 2650);
FORCEPROP 2 LAST $XR0 122 
J 0
(-2936 2650);
DISPLAY 0.638298 (-2936 2650);
PAINT MONO (-2936 2650);
FORCEPROP 2 LAST CDS_LIB standard
J 0
(-3150 2650);
PAINT MONO (-3150 2650);
DISPLAY INVISIBLE (-3150 2650);
FORCEPROP 1 LAST OFFPAGE TRUE
J 0
(-2825 2525);
DISPLAY 0.872340 (-2825 2525);
PAINT GREEN (-2825 2525);
DISPLAY INVISIBLE (-2825 2525);
FORCEPROP 1 LAST COMMENT_BODY TRUE
J 0
(-3200 2550);
DISPLAY 0.872340 (-3200 2550);
PAINT GREEN (-3200 2550);
DISPLAY INVISIBLE (-3200 2550);
FORCEPROP 2 LAST PATH I66
J 0
(-2950 2725);
DISPLAY 0.680851 (-2950 2725);
DISPLAY INVISIBLE (-2950 2725);
FORCEADD Q_RES..1
(-3925 3475);
FORCEPROP 1 LAST LOCATION R2894
J 0
(-4100 3475);
DISPLAY 0.638298 (-4100 3475);
FORCEPROP 2 LAST $SEC 1
J 0
(-3975 3675);
DISPLAY 0.680851 (-3975 3675);
PAINT MONO (-3975 3675);
DISPLAY INVISIBLE (-3975 3675);
FORCEPROP 2 LAST CDS_SEC 1
J 0
(-3975 3675);
DISPLAY 1.021277 (-3975 3675);
DISPLAY INVISIBLE (-3975 3675);
FORCEPROP 1 LASTPIN (-4025 3475) $PN 1
J 0
(-4013 3487);
DISPLAY 0.787234 (-4013 3487);
PAINT MONO (-4013 3487);
FORCEPROP 1 LASTPIN (-3825 3475) $PN 2
J 0
(-3863 3487);
DISPLAY 0.787234 (-3863 3487);
PAINT MONO (-3863 3487);
FORCEPROP 1 LAST TOLERANCE 5%
J 0
(-3700 3475);
DISPLAY 0.510638 (-3700 3475);
FORCEPROP 1 LAST MATERIAL EMPTY
J 0
(-3625 3475);
DISPLAY 0.510638 (-3625 3475);
PAINT RED (-3625 3475);
FORCEPROP 1 LAST PACK_TYPE 0402LF
J 0
(-4025 3375);
DISPLAY 0.404255 (-4025 3375);
FORCEPROP 1 LAST VALUE 0
J 2
(-3775 3475);
DISPLAY 0.510638 (-3775 3475);
FORCEPROP 1 LAST WATTAGE 1/16W
J 2
(-3800 3375);
DISPLAY 0.404255 (-3800 3375);
FORCEPROP 2 LAST CDS_LIB pure_quanta
J 0
(-3925 3475);
DISPLAY INVISIBLE (-3925 3475);
FORCEPROP 1 LAST PATH I67
J 0
(-3975 3625);
DISPLAY 0.978723 (-3975 3625);
PAINT WHITE (-3975 3625);
DISPLAY INVISIBLE (-3975 3625);
FORCEPROP 1 LAST PART_NUMBER CS00002JB13
J 0
(-4025 3425);
DISPLAY 0.404255 (-4025 3425);
DISPLAY INVISIBLE (-4025 3425);
FORCEADD Q_RES..1
(-3925 3550);
FORCEPROP 1 LAST LOCATION R2893
J 0
(-4100 3550);
DISPLAY 0.638298 (-4100 3550);
FORCEPROP 0 LAST $SEC 1
J 0
(-3800 3650);
DISPLAY 0.680851 (-3800 3650);
PAINT MONO (-3800 3650);
DISPLAY INVISIBLE (-3800 3650);
FORCEPROP 0 LAST CDS_SEC 1
J 0
(-3800 3650);
DISPLAY 1.021277 (-3800 3650);
DISPLAY INVISIBLE (-3800 3650);
FORCEPROP 1 LASTPIN (-4025 3550) $PN 1
J 0
(-4013 3562);
DISPLAY 0.787234 (-4013 3562);
PAINT MONO (-4013 3562);
FORCEPROP 1 LASTPIN (-3825 3550) $PN 2
J 0
(-3863 3562);
DISPLAY 0.787234 (-3863 3562);
PAINT MONO (-3863 3562);
FORCEPROP 1 LAST VALUE 0
J 2
(-3775 3550);
DISPLAY 0.510638 (-3775 3550);
FORCEPROP 1 LAST MATERIAL EMPTY
J 0
(-3625 3550);
DISPLAY 0.510638 (-3625 3550);
PAINT RED (-3625 3550);
FORCEPROP 1 LAST WATTAGE 1/16W
J 2
(-3800 3450);
DISPLAY 0.404255 (-3800 3450);
DISPLAY INVISIBLE (-3800 3450);
FORCEPROP 1 LAST TOLERANCE 5%
J 0
(-3700 3550);
DISPLAY 0.510638 (-3700 3550);
DISPLAY INVISIBLE (-3700 3550);
FORCEPROP 1 LAST PACK_TYPE 0402LF
J 0
(-4025 3450);
DISPLAY 0.404255 (-4025 3450);
DISPLAY INVISIBLE (-4025 3450);
FORCEPROP 2 LAST CDS_LIB pure_quanta
J 0
(-3925 3550);
DISPLAY INVISIBLE (-3925 3550);
FORCEPROP 1 LAST PATH I68
J 0
(-3975 3700);
DISPLAY 0.978723 (-3975 3700);
PAINT WHITE (-3975 3700);
DISPLAY INVISIBLE (-3975 3700);
FORCEPROP 1 LAST PART_NUMBER CS00002JB13
J 0
(-4025 3500);
DISPLAY 0.404255 (-4025 3500);
DISPLAY INVISIBLE (-4025 3500);
FORCEADD Q_RES..1
(-1800 1225);
FORCEPROP 1 LAST LOCATION R2675
J 0
(-2025 1225);
DISPLAY 0.638298 (-2025 1225);
FORCEPROP 0 LAST $SEC 1
J 0
(-2025 1275);
DISPLAY 0.680851 (-2025 1275);
PAINT MONO (-2025 1275);
DISPLAY INVISIBLE (-2025 1275);
FORCEPROP 0 LAST CDS_SEC 1
J 0
(-2025 1275);
DISPLAY 1.021277 (-2025 1275);
DISPLAY INVISIBLE (-2025 1275);
FORCEPROP 1 LASTPIN (-1900 1225) $PN 1
J 0
(-1888 1237);
DISPLAY 0.787234 (-1888 1237);
PAINT MONO (-1888 1237);
FORCEPROP 1 LASTPIN (-1700 1225) $PN 2
J 0
(-1738 1237);
DISPLAY 0.787234 (-1738 1237);
PAINT MONO (-1738 1237);
FORCEPROP 1 LAST MATERIAL CHIP
J 0
(-1500 1225);
DISPLAY 0.510638 (-1500 1225);
FORCEPROP 1 LAST VALUE 33.2
J 2
(-1600 1225);
DISPLAY 0.510638 (-1600 1225);
FORCEPROP 1 LAST TOLERANCE 1%
J 0
(-1575 1225);
DISPLAY 0.510638 (-1575 1225);
FORCEPROP 1 LAST WATTAGE 1/16W
J 2
(-1700 1325);
DISPLAY 0.404255 (-1700 1325);
DISPLAY INVISIBLE (-1700 1325);
FORCEPROP 1 LAST PACK_TYPE 0402LF
J 0
(-1925 1325);
DISPLAY 0.404255 (-1925 1325);
DISPLAY INVISIBLE (-1925 1325);
FORCEPROP 2 LAST CDS_LIB pure_quanta
J 0
(-1800 1225);
DISPLAY INVISIBLE (-1800 1225);
FORCEPROP 1 LAST PATH I69
J 0
(-1850 1375);
DISPLAY 0.978723 (-1850 1375);
PAINT WHITE (-1850 1375);
DISPLAY INVISIBLE (-1850 1375);
FORCEPROP 1 LAST PART_NUMBER CS03322FB03
J 0
(-1925 1275);
DISPLAY 0.404255 (-1925 1275);
DISPLAY INVISIBLE (-1925 1275);
FORCEADD UNIVERSAL_GND..1
(-6475 675);
FORCEPROP 3 LASTPIN (-6475 725) SIG_NAME GND\g
J 0
(-6465 735);
DISPLAY 0.659574 (-6465 735);
PAINT MONO (-6465 735);
DISPLAY INVISIBLE (-6465 735);
FORCEPROP 2 LAST CDS_LIB pure_quanta_power
J 0
(-6475 675);
DISPLAY INVISIBLE (-6475 675);
FORCEPROP 1 LAST HDL_POWER GND
J 1
(-6450 600);
DISPLAY 0.872340 (-6450 600);
PAINT GREEN (-6450 600);
DISPLAY INVISIBLE (-6450 600);
FORCEPROP 1 LAST PATH I7
J 0
(-6400 675);
DISPLAY 0.872340 (-6400 675);
PAINT AQUA (-6400 675);
DISPLAY INVISIBLE (-6400 675);
FORCEADD OFFPAGE..2
(-475 1225);
FORCEPROP 2 LAST $XR0 116 
J 0
(-286 1225);
DISPLAY 0.638298 (-286 1225);
PAINT MONO (-286 1225);
FORCEPROP 2 LAST CDS_LIB standard
J 0
(-475 1225);
DISPLAY INVISIBLE (-475 1225);
FORCEPROP 1 LAST OFFPAGE TRUE
J 0
(-150 1100);
DISPLAY 0.872340 (-150 1100);
PAINT GREEN (-150 1100);
DISPLAY INVISIBLE (-150 1100);
FORCEPROP 1 LAST COMMENT_BODY TRUE
J 0
(-520 1130);
DISPLAY 0.872340 (-520 1130);
PAINT GREEN (-520 1130);
DISPLAY INVISIBLE (-520 1130);
FORCEPROP 2 LAST PATH I71
J 0
(-300 1300);
DISPLAY 0.680851 (-300 1300);
DISPLAY INVISIBLE (-300 1300);
FORCEADD OFFPAGE..3
(-475 1125);
FORCEPROP 2 LAST $XR0 116 
J 0
(-261 1125);
DISPLAY 0.638298 (-261 1125);
PAINT MONO (-261 1125);
FORCEPROP 2 LAST CDS_LIB standard
J 0
(-475 1125);
PAINT MONO (-475 1125);
DISPLAY INVISIBLE (-475 1125);
FORCEPROP 1 LAST OFFPAGE TRUE
J 0
(-150 1000);
DISPLAY 0.872340 (-150 1000);
PAINT GREEN (-150 1000);
DISPLAY INVISIBLE (-150 1000);
FORCEPROP 1 LAST COMMENT_BODY TRUE
J 0
(-525 1025);
DISPLAY 0.872340 (-525 1025);
PAINT GREEN (-525 1025);
DISPLAY INVISIBLE (-525 1025);
FORCEPROP 2 LAST PATH I72
J 0
(-275 1200);
DISPLAY 0.680851 (-275 1200);
DISPLAY INVISIBLE (-275 1200);
FORCEADD Q_RES..1
(-1875 3900);
FORCEPROP 1 LAST LOCATION R2898
J 0
(-2100 3900);
DISPLAY 0.638298 (-2100 3900);
FORCEPROP 0 LAST $SEC 1
J 0
(-2100 3950);
DISPLAY 0.680851 (-2100 3950);
PAINT MONO (-2100 3950);
DISPLAY INVISIBLE (-2100 3950);
FORCEPROP 0 LAST CDS_SEC 1
J 0
(-2100 3950);
DISPLAY 1.021277 (-2100 3950);
DISPLAY INVISIBLE (-2100 3950);
FORCEPROP 1 LASTPIN (-1975 3900) $PN 1
J 0
(-1963 3912);
DISPLAY 0.787234 (-1963 3912);
PAINT MONO (-1963 3912);
FORCEPROP 1 LASTPIN (-1775 3900) $PN 2
J 0
(-1813 3912);
DISPLAY 0.787234 (-1813 3912);
PAINT MONO (-1813 3912);
FORCEPROP 1 LAST VALUE 33.2
J 2
(-1675 3900);
DISPLAY 0.510638 (-1675 3900);
FORCEPROP 1 LAST MATERIAL CHIP
J 0
(-1575 3900);
DISPLAY 0.510638 (-1575 3900);
FORCEPROP 1 LAST TOLERANCE 1%
J 0
(-1650 3900);
DISPLAY 0.510638 (-1650 3900);
FORCEPROP 2 LAST CDS_LIB pure_quanta
J 0
(-1875 3900);
DISPLAY INVISIBLE (-1875 3900);
FORCEPROP 1 LAST PACK_TYPE 0402LF
J 0
(-2000 4000);
DISPLAY 0.404255 (-2000 4000);
DISPLAY INVISIBLE (-2000 4000);
FORCEPROP 1 LAST WATTAGE 1/16W
J 2
(-1775 4000);
DISPLAY 0.404255 (-1775 4000);
DISPLAY INVISIBLE (-1775 4000);
FORCEPROP 1 LAST PATH I73
J 0
(-1925 4050);
DISPLAY 0.978723 (-1925 4050);
PAINT WHITE (-1925 4050);
DISPLAY INVISIBLE (-1925 4050);
FORCEPROP 1 LAST PART_NUMBER CS03322FB03
J 0
(-2000 3950);
DISPLAY 0.404255 (-2000 3950);
DISPLAY INVISIBLE (-2000 3950);
FORCEADD Q_RES..1
(-1875 4000);
FORCEPROP 1 LAST LOCATION R2897
J 0
(-2100 4000);
DISPLAY 0.638298 (-2100 4000);
FORCEPROP 0 LAST $SEC 1
J 0
(-1775 4125);
DISPLAY 0.680851 (-1775 4125);
PAINT MONO (-1775 4125);
DISPLAY INVISIBLE (-1775 4125);
FORCEPROP 0 LAST CDS_SEC 1
J 0
(-1775 4125);
DISPLAY 1.021277 (-1775 4125);
DISPLAY INVISIBLE (-1775 4125);
FORCEPROP 1 LASTPIN (-1975 4000) $PN 1
J 0
(-1963 4012);
DISPLAY 0.787234 (-1963 4012);
PAINT MONO (-1963 4012);
FORCEPROP 1 LASTPIN (-1775 4000) $PN 2
J 0
(-1813 4012);
DISPLAY 0.787234 (-1813 4012);
PAINT MONO (-1813 4012);
FORCEPROP 1 LAST WATTAGE 1/16W
J 2
(-1775 4100);
DISPLAY 0.404255 (-1775 4100);
FORCEPROP 1 LAST PACK_TYPE 0402LF
J 0
(-2000 4100);
DISPLAY 0.404255 (-2000 4100);
FORCEPROP 1 LAST TOLERANCE 1%
J 0
(-1650 4000);
DISPLAY 0.510638 (-1650 4000);
FORCEPROP 1 LAST VALUE 33.2
J 2
(-1675 4000);
DISPLAY 0.510638 (-1675 4000);
FORCEPROP 1 LAST MATERIAL CHIP
J 0
(-1575 4000);
DISPLAY 0.510638 (-1575 4000);
FORCEPROP 2 LAST CDS_LIB pure_quanta
J 0
(-1875 4000);
DISPLAY INVISIBLE (-1875 4000);
FORCEPROP 1 LAST PATH I74
J 0
(-1925 4150);
DISPLAY 0.978723 (-1925 4150);
PAINT WHITE (-1925 4150);
DISPLAY INVISIBLE (-1925 4150);
FORCEPROP 1 LAST PART_NUMBER CS03322FB03
J 0
(-2000 4050);
DISPLAY 0.404255 (-2000 4050);
DISPLAY INVISIBLE (-2000 4050);
FORCEADD OFFPAGE..2
(-550 3900);
FORCEPROP 2 LAST $XR0 122 
J 0
(-361 3900);
DISPLAY 0.638298 (-361 3900);
PAINT MONO (-361 3900);
FORCEPROP 2 LAST CDS_LIB standard
J 0
(-550 3900);
DISPLAY INVISIBLE (-550 3900);
FORCEPROP 1 LAST OFFPAGE TRUE
J 0
(-225 3775);
DISPLAY 0.872340 (-225 3775);
PAINT GREEN (-225 3775);
DISPLAY INVISIBLE (-225 3775);
FORCEPROP 1 LAST COMMENT_BODY TRUE
J 0
(-595 3805);
DISPLAY 0.872340 (-595 3805);
PAINT GREEN (-595 3805);
DISPLAY INVISIBLE (-595 3805);
FORCEPROP 2 LAST PATH I75
J 0
(-375 3975);
DISPLAY 0.680851 (-375 3975);
DISPLAY INVISIBLE (-375 3975);
FORCEADD OFFPAGE..3
(-550 4000);
FORCEPROP 2 LAST $XR0 122 
J 0
(-336 4000);
DISPLAY 0.638298 (-336 4000);
PAINT MONO (-336 4000);
FORCEPROP 2 LAST CDS_LIB standard
J 0
(-550 4000);
PAINT MONO (-550 4000);
DISPLAY INVISIBLE (-550 4000);
FORCEPROP 1 LAST OFFPAGE TRUE
J 0
(-225 3875);
DISPLAY 0.872340 (-225 3875);
PAINT GREEN (-225 3875);
DISPLAY INVISIBLE (-225 3875);
FORCEPROP 1 LAST COMMENT_BODY TRUE
J 0
(-600 3900);
DISPLAY 0.872340 (-600 3900);
PAINT GREEN (-600 3900);
DISPLAY INVISIBLE (-600 3900);
FORCEPROP 2 LAST PATH I76
J 0
(-350 4075);
DISPLAY 0.680851 (-350 4075);
DISPLAY INVISIBLE (-350 4075);
FORCEADD UNIVERSAL_GND..1
(-3175 4125);
FORCEPROP 3 LASTPIN (-3175 4175) SIG_NAME GND\g
J 0
(-3165 4185);
DISPLAY 0.659574 (-3165 4185);
PAINT MONO (-3165 4185);
DISPLAY INVISIBLE (-3165 4185);
FORCEPROP 2 LAST CDS_LIB pure_quanta_power
J 0
(-3175 4125);
PAINT MONO (-3175 4125);
DISPLAY INVISIBLE (-3175 4125);
FORCEPROP 1 LAST HDL_POWER GND
J 1
(-3150 4050);
DISPLAY 0.872340 (-3150 4050);
PAINT GREEN (-3150 4050);
DISPLAY INVISIBLE (-3150 4050);
FORCEPROP 1 LAST PATH I77
J 0
(-3100 4125);
DISPLAY 0.872340 (-3100 4125);
PAINT AQUA (-3100 4125);
DISPLAY INVISIBLE (-3100 4125);
FORCEADD Q_CAP..1
(-3175 4350);
FORCEPROP 1 LAST LOCATION C1766
J 0
(-3125 4450);
DISPLAY 0.978723 (-3125 4450);
FORCEPROP 2 LAST $SEC 1
J 0
(-3125 4550);
DISPLAY 0.680851 (-3125 4550);
PAINT MONO (-3125 4550);
DISPLAY INVISIBLE (-3125 4550);
FORCEPROP 2 LAST CDS_SEC 1
J 0
(-3125 4550);
DISPLAY 1.021277 (-3125 4550);
DISPLAY INVISIBLE (-3125 4550);
FORCEPROP 1 LASTPIN (-3175 4450) $PN 1
J 0
(-3165 4430);
DISPLAY 0.787234 (-3165 4430);
FORCEPROP 1 LASTPIN (-3175 4250) $PN 2
J 0
(-3165 4230);
DISPLAY 0.787234 (-3165 4230);
FORCEPROP 1 LAST TOLERANCE 10%
J 0
(-3125 4300);
DISPLAY 0.510638 (-3125 4300);
FORCEPROP 1 LAST VOLTAGE 25V
J 0
(-3125 4350);
DISPLAY 0.510638 (-3125 4350);
FORCEPROP 1 LAST MATERIAL X7R
J 0
(-3125 4250);
DISPLAY 0.510638 (-3125 4250);
FORCEPROP 1 LAST VALUE 0.1UF
J 0
(-3125 4400);
DISPLAY 0.510638 (-3125 4400);
FORCEPROP 1 LAST PACK_TYPE 0402
J 0
(-3125 4150);
DISPLAY 0.510638 (-3125 4150);
FORCEPROP 2 LAST CDS_LIB pure_quanta
J 0
(-3175 4350);
PAINT MONO (-3175 4350);
DISPLAY INVISIBLE (-3175 4350);
FORCEPROP 1 LAST PATH I78
J 0
(-3125 4500);
DISPLAY 0.978723 (-3125 4500);
PAINT WHITE (-3125 4500);
DISPLAY INVISIBLE (-3125 4500);
FORCEPROP 1 LAST PART_NUMBER CH4104K1B00
J 0
(-3125 4200);
DISPLAY 0.510638 (-3125 4200);
DISPLAY INVISIBLE (-3125 4200);
FORCEADD UNIVERSAL_POWER..1
(-3350 4650);
FORCEPROP 3 LASTPIN (-3350 4600) SIG_NAME P3V3_AUX\g
J 0
(-3340 4610);
DISPLAY 0.659574 (-3340 4610);
PAINT MONO (-3340 4610);
DISPLAY INVISIBLE (-3340 4610);
FORCEPROP 1 LAST HDL_POWER P3V3_AUX
J 1
(-3350 4700);
DISPLAY 0.872340 (-3350 4700);
PAINT GREEN (-3350 4700);
FORCEPROP 2 LAST CDS_LIB pure_quanta_power
J 0
(-3350 4650);
PAINT MONO (-3350 4650);
DISPLAY INVISIBLE (-3350 4650);
FORCEPROP 1 LAST PATH I79
J 0
(-3300 4675);
DISPLAY 0.872340 (-3300 4675);
PAINT AQUA (-3300 4675);
DISPLAY INVISIBLE (-3300 4675);
FORCEADD Q_RES..2
(-6475 875);
FORCEPROP 1 LAST LOCATION R2666
J 0
(-6430 1000);
DISPLAY 0.978723 (-6430 1000);
FORCEPROP 0 LAST $SEC 1
J 0
(-6425 1050);
DISPLAY 0.680851 (-6425 1050);
PAINT MONO (-6425 1050);
DISPLAY INVISIBLE (-6425 1050);
FORCEPROP 0 LAST CDS_SEC 1
J 0
(-6425 1050);
DISPLAY 1.021277 (-6425 1050);
DISPLAY INVISIBLE (-6425 1050);
FORCEPROP 1 LASTPIN (-6475 975) $PN 1
J 0
(-6470 937);
DISPLAY 0.787234 (-6470 937);
PAINT MONO (-6470 937);
FORCEPROP 1 LASTPIN (-6475 775) $PN 2
J 0
(-6470 785);
DISPLAY 0.787234 (-6470 785);
PAINT MONO (-6470 785);
FORCEPROP 1 LAST WATTAGE 1/16W
J 0
(-6435 850);
DISPLAY 0.510638 (-6435 850);
FORCEPROP 1 LAST MATERIAL CHIP
J 0
(-6435 800);
DISPLAY 0.510638 (-6435 800);
FORCEPROP 1 LAST TOLERANCE 1%
J 0
(-6430 900);
DISPLAY 0.510638 (-6430 900);
FORCEPROP 1 LAST VALUE 10K
J 0
(-6430 950);
DISPLAY 0.510638 (-6430 950);
FORCEPROP 1 LAST PACK_TYPE 0402LF
J 0
(-6435 750);
DISPLAY 0.510638 (-6435 750);
FORCEPROP 2 LAST CDS_LIB pure_quanta
J 0
(-6475 875);
DISPLAY INVISIBLE (-6475 875);
FORCEPROP 1 LAST PATH I8
J 0
(-6425 1050);
DISPLAY 0.978723 (-6425 1050);
PAINT WHITE (-6425 1050);
DISPLAY INVISIBLE (-6425 1050);
FORCEPROP 1 LAST PART_NUMBER CS31002FB08
J 0
(-6435 700);
DISPLAY 0.510638 (-6435 700);
DISPLAY INVISIBLE (-6435 700);
FORCEADD Q_RES..2
(-2425 4325);
FORCEPROP 1 LAST LOCATION R3523
J 0
(-2380 4450);
DISPLAY 0.510638 (-2380 4450);
FORCEPROP 0 LAST $SEC 1
J 0
(-2375 4475);
DISPLAY 0.680851 (-2375 4475);
PAINT MONO (-2375 4475);
DISPLAY INVISIBLE (-2375 4475);
FORCEPROP 0 LAST CDS_SEC 1
J 0
(-2375 4475);
DISPLAY 1.021277 (-2375 4475);
DISPLAY INVISIBLE (-2375 4475);
FORCEPROP 1 LASTPIN (-2425 4425) $PN 1
J 0
(-2420 4387);
DISPLAY 0.787234 (-2420 4387);
PAINT MONO (-2420 4387);
FORCEPROP 1 LASTPIN (-2425 4225) $PN 2
J 0
(-2420 4235);
DISPLAY 0.787234 (-2420 4235);
PAINT MONO (-2420 4235);
FORCEPROP 1 LAST WATTAGE 1/16W
J 0
(-2385 4300);
DISPLAY 0.404255 (-2385 4300);
FORCEPROP 1 LAST TOLERANCE 1%
J 0
(-2380 4350);
DISPLAY 0.404255 (-2380 4350);
FORCEPROP 1 LAST VALUE 54.9K
J 0
(-2380 4400);
DISPLAY 0.404255 (-2380 4400);
FORCEPROP 1 LAST PACK_TYPE 0402LF
J 0
(-2385 4150);
DISPLAY 0.404255 (-2385 4150);
FORCEPROP 1 LAST MATERIAL CHIP
J 0
(-2385 4250);
DISPLAY 0.404255 (-2385 4250);
FORCEPROP 2 LAST CDS_LIB pure_quanta
J 0
(-2425 4325);
DISPLAY INVISIBLE (-2425 4325);
FORCEPROP 1 LAST PATH I80
J 0
(-2375 4500);
DISPLAY 0.978723 (-2375 4500);
PAINT WHITE (-2375 4500);
DISPLAY INVISIBLE (-2375 4500);
FORCEPROP 1 LAST PART_NUMBER CS35492FB03
J 0
(-2385 4200);
DISPLAY 0.404255 (-2385 4200);
DISPLAY INVISIBLE (-2385 4200);
FORCEADD Q_RES..2
(-2175 4325);
FORCEPROP 1 LAST LOCATION R3524
J 0
(-2130 4450);
DISPLAY 0.978723 (-2130 4450);
FORCEPROP 0 LAST $SEC 1
J 0
(-2125 4500);
DISPLAY 0.680851 (-2125 4500);
PAINT MONO (-2125 4500);
DISPLAY INVISIBLE (-2125 4500);
FORCEPROP 0 LAST CDS_SEC 1
J 0
(-2125 4500);
DISPLAY 1.021277 (-2125 4500);
DISPLAY INVISIBLE (-2125 4500);
FORCEPROP 1 LASTPIN (-2175 4425) $PN 1
J 0
(-2170 4387);
DISPLAY 0.787234 (-2170 4387);
PAINT MONO (-2170 4387);
FORCEPROP 1 LASTPIN (-2175 4225) $PN 2
J 0
(-2170 4235);
DISPLAY 0.787234 (-2170 4235);
PAINT MONO (-2170 4235);
FORCEPROP 1 LAST PACK_TYPE 0402LF
J 0
(-2135 4150);
DISPLAY 0.404255 (-2135 4150);
FORCEPROP 1 LAST VALUE 54.9K
J 0
(-2130 4400);
DISPLAY 0.404255 (-2130 4400);
FORCEPROP 1 LAST TOLERANCE 1%
J 0
(-2130 4350);
DISPLAY 0.404255 (-2130 4350);
FORCEPROP 1 LAST WATTAGE 1/16W
J 0
(-2135 4300);
DISPLAY 0.404255 (-2135 4300);
FORCEPROP 1 LAST MATERIAL CHIP
J 0
(-2135 4250);
DISPLAY 0.404255 (-2135 4250);
FORCEPROP 2 LAST CDS_LIB pure_quanta
J 0
(-2175 4325);
DISPLAY INVISIBLE (-2175 4325);
FORCEPROP 1 LAST PATH I81
J 0
(-2125 4500);
DISPLAY 0.978723 (-2125 4500);
PAINT WHITE (-2125 4500);
DISPLAY INVISIBLE (-2125 4500);
FORCEPROP 1 LAST PART_NUMBER CS35492FB03
J 0
(-2135 4200);
DISPLAY 0.404255 (-2135 4200);
DISPLAY INVISIBLE (-2135 4200);
FORCEADD UNIVERSAL_POWER..1
(-2425 4650);
FORCEPROP 3 LASTPIN (-2425 4600) SIG_NAME P3V3_AUX\g
J 0
(-2415 4610);
DISPLAY 0.659574 (-2415 4610);
PAINT MONO (-2415 4610);
DISPLAY INVISIBLE (-2415 4610);
FORCEPROP 1 LAST HDL_POWER P3V3_AUX
J 1
(-2425 4700);
DISPLAY 0.872340 (-2425 4700);
PAINT GREEN (-2425 4700);
FORCEPROP 2 LAST CDS_LIB pure_quanta_power
J 0
(-2425 4650);
PAINT MONO (-2425 4650);
DISPLAY INVISIBLE (-2425 4650);
FORCEPROP 1 LAST PATH I82
J 0
(-2375 4675);
DISPLAY 0.872340 (-2375 4675);
PAINT AQUA (-2375 4675);
DISPLAY INVISIBLE (-2375 4675);
FORCEADD OFFPAGE..2
(-2925 5275);
FORCEPROP 2 LAST $XR0 119 
J 0
(-2736 5275);
DISPLAY 0.638298 (-2736 5275);
PAINT MONO (-2736 5275);
FORCEPROP 2 LAST CDS_LIB standard
J 0
(-2925 5275);
DISPLAY INVISIBLE (-2925 5275);
FORCEPROP 1 LAST OFFPAGE TRUE
J 0
(-2600 5150);
DISPLAY 0.872340 (-2600 5150);
PAINT GREEN (-2600 5150);
DISPLAY INVISIBLE (-2600 5150);
FORCEPROP 1 LAST COMMENT_BODY TRUE
J 0
(-2970 5180);
DISPLAY 0.872340 (-2970 5180);
PAINT GREEN (-2970 5180);
DISPLAY INVISIBLE (-2970 5180);
FORCEPROP 2 LAST PATH I83
J 0
(-2725 5325);
DISPLAY 0.680851 (-2725 5325);
DISPLAY INVISIBLE (-2725 5325);
FORCEADD OFFPAGE..3
(-2925 5375);
FORCEPROP 2 LAST $XR0 119 
J 0
(-2711 5375);
DISPLAY 0.638298 (-2711 5375);
PAINT MONO (-2711 5375);
FORCEPROP 2 LAST CDS_LIB standard
J 0
(-2925 5375);
PAINT MONO (-2925 5375);
DISPLAY INVISIBLE (-2925 5375);
FORCEPROP 1 LAST OFFPAGE TRUE
J 0
(-2600 5250);
DISPLAY 0.872340 (-2600 5250);
PAINT GREEN (-2600 5250);
DISPLAY INVISIBLE (-2600 5250);
FORCEPROP 1 LAST COMMENT_BODY TRUE
J 0
(-2975 5275);
DISPLAY 0.872340 (-2975 5275);
PAINT GREEN (-2975 5275);
DISPLAY INVISIBLE (-2975 5275);
FORCEPROP 2 LAST PATH I84
J 0
(-2700 5425);
DISPLAY 0.680851 (-2700 5425);
DISPLAY INVISIBLE (-2700 5425);
FORCEADD Q_RES..1
(-5700 1125);
FORCEPROP 1 LAST LOCATION R3111
J 0
(-5925 1125);
DISPLAY 0.638298 (-5925 1125);
FORCEPROP 0 LAST $SEC 1
J 0
(-5925 1175);
DISPLAY 0.680851 (-5925 1175);
PAINT MONO (-5925 1175);
DISPLAY INVISIBLE (-5925 1175);
FORCEPROP 0 LAST CDS_SEC 1
J 0
(-5925 1175);
DISPLAY 0.680851 (-5925 1175);
DISPLAY INVISIBLE (-5925 1175);
FORCEPROP 1 LASTPIN (-5800 1125) $PN 1
J 0
(-5788 1137);
DISPLAY 0.787234 (-5788 1137);
PAINT MONO (-5788 1137);
FORCEPROP 1 LASTPIN (-5600 1125) $PN 2
J 0
(-5638 1137);
DISPLAY 0.787234 (-5638 1137);
PAINT MONO (-5638 1137);
FORCEPROP 1 LAST PACK_TYPE 0402LF
J 0
(-5300 1125);
DISPLAY 0.404255 (-5300 1125);
FORCEPROP 1 LAST MATERIAL CHIP
J 0
(-5425 1125);
DISPLAY 0.510638 (-5425 1125);
FORCEPROP 1 LAST TOLERANCE 5%
J 0
(-5500 1125);
DISPLAY 0.510638 (-5500 1125);
FORCEPROP 1 LAST VALUE 0
J 2
(-5550 1125);
DISPLAY 0.510638 (-5550 1125);
FORCEPROP 1 LAST WATTAGE 1/16W
J 2
(-5575 1175);
DISPLAY 0.404255 (-5575 1175);
DISPLAY INVISIBLE (-5575 1175);
FORCEPROP 2 LAST CDS_LIB pure_quanta
J 0
(-5700 1125);
DISPLAY INVISIBLE (-5700 1125);
FORCEPROP 1 LAST PATH I85
J 0
(-5750 1275);
DISPLAY 0.978723 (-5750 1275);
PAINT WHITE (-5750 1275);
DISPLAY INVISIBLE (-5750 1275);
FORCEPROP 1 LAST PART_NUMBER CS00002JB13
J 0
(-5800 1225);
DISPLAY 0.404255 (-5800 1225);
DISPLAY INVISIBLE (-5800 1225);
FORCEADD Q_RES..1
(-1800 1125);
FORCEPROP 1 LAST LOCATION R2674
J 0
(-2050 1125);
DISPLAY 0.638298 (-2050 1125);
FORCEPROP 0 LAST $SEC 1
J 0
(-2050 1175);
DISPLAY 0.680851 (-2050 1175);
PAINT MONO (-2050 1175);
DISPLAY INVISIBLE (-2050 1175);
FORCEPROP 0 LAST CDS_SEC 1
J 0
(-2050 1175);
DISPLAY 0.680851 (-2050 1175);
DISPLAY INVISIBLE (-2050 1175);
FORCEPROP 1 LASTPIN (-1900 1125) $PN 1
J 0
(-1888 1137);
DISPLAY 0.787234 (-1888 1137);
PAINT MONO (-1888 1137);
FORCEPROP 1 LASTPIN (-1700 1125) $PN 2
J 0
(-1738 1137);
DISPLAY 0.787234 (-1738 1137);
PAINT MONO (-1738 1137);
FORCEPROP 1 LAST MATERIAL CHIP
J 0
(-1475 1125);
DISPLAY 0.510638 (-1475 1125);
FORCEPROP 1 LAST TOLERANCE 5%
J 0
(-1550 1125);
DISPLAY 0.510638 (-1550 1125);
FORCEPROP 1 LAST VALUE 27
J 2
(-1600 1125);
DISPLAY 0.510638 (-1600 1125);
FORCEPROP 1 LAST WATTAGE 1/16W
J 2
(-1675 1075);
DISPLAY 0.404255 (-1675 1075);
FORCEPROP 1 LAST PACK_TYPE 0402LF
J 0
(-1925 1075);
DISPLAY 0.404255 (-1925 1075);
FORCEPROP 2 LAST CDS_LIB pure_quanta
J 0
(-1800 1125);
DISPLAY INVISIBLE (-1800 1125);
FORCEPROP 1 LAST PATH I86
J 0
(-1850 1275);
DISPLAY 0.978723 (-1850 1275);
PAINT WHITE (-1850 1275);
DISPLAY INVISIBLE (-1850 1275);
FORCEPROP 1 LAST PART_NUMBER CS02702JB02
J 0
(-1900 1050);
DISPLAY 0.404255 (-1900 1050);
DISPLAY INVISIBLE (-1900 1050);
FORCEADD OFFPAGE..6
(-6600 1125);
FORCEPROP 2 LAST $XR1 151 
J 0
(-7030 1125);
DISPLAY 0.638298 (-7030 1125);
PAINT MONO (-7030 1125);
FORCEPROP 2 LAST $XR0 150 
J 0
(-6910 1125);
DISPLAY 0.638298 (-6910 1125);
PAINT MONO (-6910 1125);
FORCEPROP 2 LAST CDS_LIB standard
J 0
(-6600 1125);
PAINT MONO (-6600 1125);
DISPLAY INVISIBLE (-6600 1125);
FORCEPROP 1 LAST OFFPAGE TRUE
J 0
(-6275 1000);
DISPLAY 0.872340 (-6275 1000);
DISPLAY INVISIBLE (-6275 1000);
FORCEPROP 1 LAST COMMENT_BODY TRUE
J 0
(-6500 1050);
DISPLAY 0.872340 (-6500 1050);
PAINT GREEN (-6500 1050);
DISPLAY INVISIBLE (-6500 1050);
FORCEPROP 2 LAST PATH I9
J 0
(-6550 1200);
DISPLAY 0.680851 (-6550 1200);
DISPLAY INVISIBLE (-6550 1200);
FORCEADD DNS..2
(-2350 1575);
PAINT RED (-2350 1575);
FORCEPROP 2 LAST CDS_LIB mstr_misc
J 0
(-2350 1575);
DISPLAY INVISIBLE (-2350 1575);
FORCEPROP 1 LAST COMMENT_BODY TRUE
J 0
(-2350 1575);
DISPLAY INVISIBLE (-2350 1575);
FORCEADD DNS..2
(-2100 1575);
PAINT RED (-2100 1575);
FORCEPROP 2 LAST CDS_LIB mstr_misc
J 0
(-2100 1575);
DISPLAY INVISIBLE (-2100 1575);
FORCEPROP 1 LAST COMMENT_BODY TRUE
J 0
(-2100 1575);
DISPLAY INVISIBLE (-2100 1575);
FORCEADD DNS..2
(-3925 3500);
PAINT RED (-3925 3500);
FORCEPROP 2 LAST CDS_LIB mstr_misc
J 0
(-3925 3500);
DISPLAY INVISIBLE (-3925 3500);
FORCEPROP 1 LAST COMMENT_BODY TRUE
J 0
(-3925 3500);
DISPLAY INVISIBLE (-3925 3500);
FORCEADD QUANTA_TITLE_BLOCK_C..1
(0 0);
FORCEPROP 0 LAST CDS_CON_LAST_MODIFIED Thu Sep 14 16:12:34 2023
J 0
(-1885 15);
DISPLAY INVISIBLE (-1885 15);
FORCEPROP 1 LAST CUSTOM_TXT_CDS <CON_LAST_MODIFIED>
J 0
(-1885 15);
DISPLAY 0.978723 (-1885 15);
FORCEPROP 2 LAST CUSTOM_TXT_CDS <XR_PAGE_TITLE>
J 0
(-7890 5250);
DISPLAY 0.638298 (-7890 5250);
PAINT PINK (-7890 5250);
DISPLAY INVISIBLE (-7890 5250);
FORCEPROP 1 LAST CUSTOM_TXT_CDS <NAME_2>
J 0
(-3175 50);
FORCEPROP 1 LAST CUSTOM_TXT_CDS <NAME_1>
J 0
(-3175 175);
FORCEPROP 1 LAST CUSTOM_TXT_CDS <Q_NUMBER>
J 0
(-1403 103);
DISPLAY 1.212766 (-1403 103);
FORCEPROP 1 LAST CUSTOM_TXT_CDS <Q_PROJ>
J 0
(-2382 102);
DISPLAY 1.212766 (-2382 102);
FORCEPROP 1 LAST CUSTOM_TXT_CDS <Q_REV>
J 0
(-184 103);
DISPLAY 1.212766 (-184 103);
FORCEPROP 1 LAST CUSTOM_TXT_CDS <CON_PAGE_NUM> OF <CON_TOTAL_PAGES>
J 0
(-446 18);
DISPLAY 0.978723 (-446 18);
FORCEPROP 1 LAST Q_TITLE SMBUS - PCIE3  SMBUS
J 0
(-9366 26);
DISPLAY 2.446809 (-9366 26);
PAINT GREEN (-9366 26);
FORCEPROP 1 LAST CDS_LMAN_SYM_OUTLINE -9475,6775,100,-125
J 0
(0 0);
DISPLAY 0.468085 (0 0);
PAINT GREEN (0 0);
DISPLAY INVISIBLE (0 0);
FORCEPROP 2 LAST CDS_LIB pure_quanta
J 0
(0 0);
DISPLAY INVISIBLE (0 0);
FORCEPROP 2 LAST PAGE_BORDER TRUE
J 0
(-7890 5250);
DISPLAY 0.638298 (-7890 5250);
PAINT PINK (-7890 5250);
DISPLAY INVISIBLE (-7890 5250);
FORCEPROP 2 LAST CDS_XR_PAGE_TITLE CR-249 : @T6G_MB_LIB.T6G(SCH_1):PAGE249
J 0
(-7890 5250);
DISPLAY 0.638298 (-7890 5250);
PAINT PINK (-7890 5250);
DISPLAY INVISIBLE (-7890 5250);
FORCEPROP 1 LAST Q_DEPT BU9
J 1
(-3763 49);
DISPLAY 1.957447 (-3763 49);
PAINT GREEN (-3763 49);
DISPLAY INVISIBLE (-3763 49);
FORCEPROP 1 LAST COMMENT_BODY TRUE
J 0
(12 -13);
DISPLAY 0.978723 (12 -13);
PAINT GREEN (12 -13);
DISPLAY INVISIBLE (12 -13);
FORCEADD DNS..2
(-6525 2150);
PAINT RED (-6525 2150);
FORCEPROP 2 LAST CDS_LIB mstr_misc
J 0
(-6525 2150);
DISPLAY INVISIBLE (-6525 2150);
FORCEPROP 1 LAST COMMENT_BODY TRUE
J 0
(-6525 2150);
DISPLAY INVISIBLE (-6525 2150);
FORCEADD DNS..2
(-6300 4875);
PAINT RED (-6300 4875);
FORCEPROP 2 LAST CDS_LIB mstr_misc
J 0
(-6300 4875);
DISPLAY INVISIBLE (-6300 4875);
FORCEPROP 1 LAST COMMENT_BODY TRUE
J 0
(-6300 4875);
DISPLAY INVISIBLE (-6300 4875);
FORCEADD DNS..2
(-3950 1175);
PAINT RED (-3950 1175);
FORCEPROP 2 LAST CDS_LIB mstr_misc
J 0
(-3950 1175);
DISPLAY INVISIBLE (-3950 1175);
FORCEPROP 1 LAST COMMENT_BODY TRUE
J 0
(-3950 1175);
DISPLAY INVISIBLE (-3950 1175);
WIRE 16 -1 (-6900 2375)(-6900 2450);
WIRE 16 -1 (-6700 3575)(-6700 3525);
WIRE 16 -1 (-4325 1025)(-4475 1025);
WIRE 16 -1 (-4475 1025)(-4475 950);
WIRE 16 -1 (-5775 2900)(-5775 2825);
WIRE 16 -1 (-6675 5100)(-6675 5175);
WIRE 16 -1 (-5650 5625)(-5650 5550);
WIRE 16 -1 (-3275 1525)(-3275 1450);
WIRE 16 -1 (-6475 775)(-6475 725);
WIRE 16 -1 (-3175 4250)(-3175 4175);
WIRE 16 -1 (-5850 4100)(-6700 4100);
FORCEPROP 2 LAST SIG_NAME SMB_BMC_GPU_EN
J 0
(-6485 4110);
DISPLAY 0.510638 (-6485 4110);
PAINT WHITE (-6485 4110);
WIRE 16 -1 (-6700 4100)(-6875 4100);
WIRE 16 -1 (-6700 4100)(-6700 3775);
WIRE 16 -1 (-5850 3900)(-6875 3900);
FORCEPROP 0 LAST CDS_PHYS_NET_NAME SMB_1_BMC_GPU_SDA
J 0
(-6760 3948);
PAINT MONO (-6760 3948);
DISPLAY INVISIBLE (-6760 3948);
FORCEPROP 2 LAST SIG_NAME SMB_1_BMC_GPU_SDA
J 2
(-6085 3910);
DISPLAY 0.510638 (-6085 3910);
PAINT WHITE (-6085 3910);
WIRE 16 -1 (-5325 2550)(-4775 2550);
WIRE 16 -1 (-5325 2125)(-5325 2550);
WIRE 16 -1 (-5325 2550)(-6100 2550);
FORCEPROP 0 LAST CDS_PHYS_NET_NAME SMB_2_BMC_GPU_BUF_R_SDA
J 0
(-5985 2598);
PAINT MONO (-5985 2598);
DISPLAY INVISIBLE (-5985 2598);
FORCEPROP 2 LAST SIG_NAME SMB_2_BMC_GPU_BUF_R_SDA
J 0
(-6010 2560);
DISPLAY 0.510638 (-6010 2560);
PAINT WHITE (-6010 2560);
FORCEPROP 2 LASTPROP $XRERR UNIQUE?
J 0
(-6250 2560);
DISPLAY 0.638298 (-6250 2560);
PAINT MONO (-6250 2560);
DISPLAY INVISIBLE (-6250 2560);
WIRE 16 -1 (-4575 2550)(-4775 2550);
WIRE 16 -1 (-4775 2875)(-4775 2550);
WIRE 16 -1 (-5325 2125)(-6425 2125);
WIRE 16 -1 (-525 1125)(-1700 1125);
FORCEPROP 0 LAST CDS_PHYS_NET_NAME I3C_BMC_SWB_BUF_SDA
J 0
(-1585 1173);
PAINT MONO (-1585 1173);
DISPLAY INVISIBLE (-1585 1173);
FORCEPROP 2 LAST SIG_NAME I3C_BMC_SWB_BUF_SDA
J 0
(-1135 1135);
DISPLAY 0.510638 (-1135 1135);
PAINT WHITE (-1135 1135);
WIRE 16 -1 (-6625 2125)(-7300 2125);
WIRE 16 -1 (-7300 2550)(-7300 2125);
WIRE 16 -1 (-6900 2550)(-7300 2550);
WIRE 16 -1 (-7300 2550)(-7725 2550);
FORCEPROP 2 LAST SIG_NAME SMB_2_BMC_GPU_R_SDA
J 0
(-7460 2560);
DISPLAY 0.404255 (-7460 2560);
PAINT WHITE (-7460 2560);
FORCEPROP 2 LASTPROP $XRERR UNIQUE?
J 0
(-7700 2560);
DISPLAY 0.638298 (-7700 2560);
PAINT MONO (-7700 2560);
DISPLAY INVISIBLE (-7700 2560);
WIRE 16 -1 (-7200 2200)(-6625 2200);
WIRE 16 -1 (-7200 2650)(-7200 2200);
WIRE 16 -1 (-6900 2650)(-7200 2650);
WIRE 16 -1 (-7200 2650)(-7725 2650);
FORCEPROP 2 LAST SIG_NAME SMB_2_BMC_GPU_R_SCL
J 0
(-7462 2660);
DISPLAY 0.404255 (-7462 2660);
PAINT WHITE (-7462 2660);
FORCEPROP 2 LASTPROP $XRERR UNIQUE?
J 0
(-7702 2660);
DISPLAY 0.638298 (-7702 2660);
PAINT MONO (-7702 2660);
DISPLAY INVISIBLE (-7702 2660);
WIRE 16 -1 (-5425 2200)(-5425 2650);
WIRE 16 -1 (-6425 2200)(-5425 2200);
WIRE 16 -1 (-5425 2650)(-5025 2650);
WIRE 16 -1 (-5425 2650)(-6100 2650);
FORCEPROP 0 LAST CDS_PHYS_NET_NAME SMB_2_BMC_GPU_BUF_R_SCL
J 0
(-5985 2698);
PAINT MONO (-5985 2698);
DISPLAY INVISIBLE (-5985 2698);
FORCEPROP 2 LAST SIG_NAME SMB_2_BMC_GPU_BUF_R_SCL
J 0
(-6010 2660);
DISPLAY 0.510638 (-6010 2660);
PAINT WHITE (-6010 2660);
FORCEPROP 2 LASTPROP $XRERR UNIQUE?
J 0
(-6250 2660);
DISPLAY 0.638298 (-6250 2660);
PAINT MONO (-6250 2660);
DISPLAY INVISIBLE (-6250 2660);
WIRE 16 -1 (-4575 2650)(-5025 2650);
WIRE 16 -1 (-5025 2875)(-5025 2650);
WIRE 16 -1 (-5775 3100)(-5775 3175);
WIRE 16 -1 (-5950 3175)(-5775 3175);
WIRE 16 -1 (-5950 3175)(-5950 2750);
WIRE 16 -1 (-5950 3175)(-5950 3250);
WIRE 16 -1 (-5950 2750)(-6100 2750);
WIRE 16 -1 (-5600 1325)(-4325 1325);
FORCEPROP 0 LAST CDS_PHYS_NET_NAME SMB_BMC_SWB_EN_R2
J 0
(-2735 1373);
PAINT MONO (-2735 1373);
DISPLAY INVISIBLE (-2735 1373);
FORCEPROP 2 LAST SIG_NAME SMB_BMC_SWB_EN_R2
J 0
(-5185 1335);
DISPLAY 0.510638 (-5185 1335);
PAINT WHITE (-5185 1335);
FORCEPROP 2 LASTPROP $XRERR UNIQUE?
J 0
(-5425 1335);
DISPLAY 0.638298 (-5425 1335);
PAINT MONO (-5425 1335);
DISPLAY INVISIBLE (-5425 1335);
WIRE 16 -1 (-4650 400)(-4075 400);
WIRE 16 -1 (-4650 1225)(-4650 400);
WIRE 16 -1 (-4325 1225)(-4650 1225);
FORCEPROP 2 LAST SIG_NAME I3C_BMC_SWB_R_SCL
J 2
(-4635 1235);
DISPLAY 0.510638 (-4635 1235);
PAINT WHITE (-4635 1235);
FORCEPROP 2 LASTPROP $XRERR UNIQUE?
J 0
(-4875 1235);
DISPLAY 0.638298 (-4875 1235);
PAINT MONO (-4875 1235);
DISPLAY INVISIBLE (-4875 1235);
WIRE 16 -1 (-4650 1225)(-5600 1225);
FORCEPROP 0 LAST CDS_PHYS_NET_NAME I3C_BMC_SWB_R_SCL
J 0
(-6285 1273);
PAINT MONO (-6285 1273);
DISPLAY INVISIBLE (-6285 1273);
WIRE 16 -1 (-4525 475)(-4075 475);
WIRE 16 -1 (-4525 1125)(-4525 475);
WIRE 16 -1 (-4325 1125)(-4525 1125);
WIRE 16 -1 (-5600 1125)(-4525 1125);
FORCEPROP 0 LAST CDS_PHYS_NET_NAME I3C_BMC_SWB_R_SDA
J 0
(-6285 1173);
PAINT MONO (-6285 1173);
DISPLAY INVISIBLE (-6285 1173);
FORCEPROP 2 LAST SIG_NAME I3C_BMC_SWB_R_SDA
J 2
(-4635 1135);
DISPLAY 0.510638 (-4635 1135);
PAINT WHITE (-4635 1135);
FORCEPROP 2 LASTPROP $XRERR UNIQUE?
J 0
(-4875 1135);
DISPLAY 0.638298 (-4875 1135);
PAINT MONO (-4875 1135);
DISPLAY INVISIBLE (-4875 1135);
WIRE 16 -1 (-6400 4850)(-7075 4850);
WIRE 16 -1 (-7075 5275)(-7075 4850);
WIRE 16 -1 (-6675 5275)(-7075 5275);
FORCEPROP 2 LAST SIG_NAME SMB_BMC_SWB_R_SDA
J 0
(-7310 5285);
DISPLAY 0.510638 (-7310 5285);
PAINT WHITE (-7310 5285);
FORCEPROP 2 LASTPROP $XRERR UNIQUE?
J 0
(-7550 5285);
DISPLAY 0.638298 (-7550 5285);
PAINT MONO (-7550 5285);
DISPLAY INVISIBLE (-7550 5285);
WIRE 16 -1 (-7075 5275)(-7675 5275);
WIRE 16 -1 (-6675 5375)(-6975 5375);
FORCEPROP 2 LAST SIG_NAME SMB_BMC_SWB_R_SCL
J 0
(-7310 5385);
DISPLAY 0.510638 (-7310 5385);
PAINT WHITE (-7310 5385);
FORCEPROP 2 LASTPROP $XRERR UNIQUE?
J 0
(-7550 5385);
DISPLAY 0.638298 (-7550 5385);
PAINT MONO (-7550 5385);
DISPLAY INVISIBLE (-7550 5385);
WIRE 16 -1 (-6975 5375)(-6975 4925);
WIRE 16 -1 (-6975 5375)(-7675 5375);
WIRE 16 -1 (-6975 4925)(-6400 4925);
WIRE 16 -1 (-6675 5475)(-7675 5475);
FORCEPROP 0 LAST CDS_PHYS_NET_NAME SMB_BMC_SWB_EN_R
J 0
(-7635 5523);
PAINT MONO (-7635 5523);
DISPLAY INVISIBLE (-7635 5523);
FORCEPROP 2 LAST SIG_NAME SMB_BMC_SWB_EN_R
J 0
(-7310 5485);
DISPLAY 0.510638 (-7310 5485);
PAINT WHITE (-7310 5485);
FORCEPROP 2 LASTPROP $XRERR UNIQUE?
J 0
(-7550 5485);
DISPLAY 0.638298 (-7550 5485);
PAINT MONO (-7550 5485);
DISPLAY INVISIBLE (-7550 5485);
WIRE 16 -1 (-5875 5475)(-5825 5475);
WIRE 16 -1 (-5825 5900)(-5825 5475);
WIRE 16 -1 (-5825 5900)(-5650 5900);
WIRE 16 -1 (-5825 5900)(-5825 5975);
WIRE 16 -1 (-5650 5825)(-5650 5900);
WIRE 16 -1 (-3375 1800)(-3275 1800);
WIRE 16 -1 (-3450 1800)(-3375 1800);
WIRE 16 -1 (-3375 1800)(-3375 1325);
WIRE 16 -1 (-3275 1725)(-3275 1800);
WIRE 16 -1 (-3375 1325)(-3525 1325);
WIRE 16 -1 (-3450 1800)(-3450 1875);
WIRE 16 -1 (-3875 400)(-2425 400);
WIRE 16 -1 (-2425 400)(-2425 1225);
WIRE 16 -1 (-2100 1225)(-2425 1225);
WIRE 16 -1 (-2425 1225)(-3525 1225);
FORCEPROP 0 LAST CDS_PHYS_NET_NAME I3C_BMC_SWB_BUF_R_SCL
J 0
(-3410 1273);
PAINT MONO (-3410 1273);
DISPLAY INVISIBLE (-3410 1273);
FORCEPROP 2 LAST SIG_NAME I3C_BMC_SWB_BUF_R_SCL
J 0
(-3360 1235);
DISPLAY 0.510638 (-3360 1235);
PAINT WHITE (-3360 1235);
FORCEPROP 2 LASTPROP $XRERR UNIQUE?
J 0
(-3600 1235);
DISPLAY 0.638298 (-3600 1235);
PAINT MONO (-3600 1235);
DISPLAY INVISIBLE (-3600 1235);
WIRE 16 -1 (-1900 1225)(-2100 1225);
WIRE 16 -1 (-2100 1500)(-2100 1225);
WIRE 16 -1 (-2350 1500)(-2350 1125);
WIRE 16 -1 (-1900 1125)(-2350 1125);
WIRE 16 -1 (-2350 1125)(-2550 1125);
WIRE 16 -1 (-2550 475)(-2550 1125);
WIRE 16 -1 (-2550 1125)(-3525 1125);
FORCEPROP 0 LAST CDS_PHYS_NET_NAME I3C_BMC_SWB_BUF_R_SDA
J 0
(-3410 1173);
PAINT MONO (-3410 1173);
DISPLAY INVISIBLE (-3410 1173);
FORCEPROP 2 LAST SIG_NAME I3C_BMC_SWB_BUF_R_SDA
J 0
(-3360 1135);
DISPLAY 0.510638 (-3360 1135);
PAINT WHITE (-3360 1135);
FORCEPROP 2 LASTPROP $XRERR UNIQUE?
J 0
(-3600 1135);
DISPLAY 0.638298 (-3600 1135);
PAINT MONO (-3600 1135);
DISPLAY INVISIBLE (-3600 1135);
WIRE 16 -1 (-3875 475)(-2550 475);
WIRE 16 -1 (-525 1225)(-1700 1225);
FORCEPROP 0 LAST CDS_PHYS_NET_NAME I3C_BMC_SWB_BUF_SCL
J 0
(-1585 1273);
PAINT MONO (-1585 1273);
DISPLAY INVISIBLE (-1585 1273);
FORCEPROP 2 LAST SIG_NAME I3C_BMC_SWB_BUF_SCL
J 0
(-1135 1235);
DISPLAY 0.510638 (-1135 1235);
PAINT WHITE (-1135 1235);
WIRE 16 -1 (-5800 1125)(-6550 1125);
FORCEPROP 2 LAST SIG_NAME I3C_BMC_SWB_SDA
J 0
(-6435 1135);
DISPLAY 0.510638 (-6435 1135);
PAINT WHITE (-6435 1135);
WIRE 16 -1 (-5800 1225)(-6550 1225);
FORCEPROP 2 LAST SIG_NAME I3C_BMC_SWB_SCL
J 0
(-6435 1235);
DISPLAY 0.510638 (-6435 1235);
PAINT WHITE (-6435 1235);
WIRE 16 -1 (-5800 1325)(-6475 1325);
FORCEPROP 2 LAST SIG_NAME SMB_BMC_SWB_EN
J 0
(-6435 1335);
DISPLAY 0.510638 (-6435 1335);
PAINT WHITE (-6435 1335);
WIRE 16 -1 (-6475 1325)(-6550 1325);
WIRE 16 -1 (-6475 1325)(-6475 975);
WIRE 16 -1 (-4775 3075)(-4775 3200);
WIRE 16 -1 (-5025 3200)(-4775 3200);
WIRE 16 -1 (-5025 3075)(-5025 3200);
WIRE 16 -1 (-5025 3200)(-5025 3250);
WIRE 16 -1 (-4375 3800)(-4300 3800);
WIRE 16 -1 (-4375 3725)(-4375 3800);
WIRE 16 -1 (-4550 5800)(-4550 5925);
WIRE 16 -1 (-4800 5925)(-4550 5925);
WIRE 16 -1 (-4800 5800)(-4800 5925);
WIRE 16 -1 (-4800 5925)(-4800 5975);
WIRE 16 -1 (-2100 1700)(-2100 1825);
WIRE 16 -1 (-2350 1825)(-2100 1825);
WIRE 16 -1 (-2350 1700)(-2350 1825);
WIRE 16 -1 (-2350 1825)(-2350 1875);
WIRE 16 -1 (-3350 4100)(-3500 4100);
WIRE 16 -1 (-3350 4525)(-3350 4100);
WIRE 16 -1 (-3350 4525)(-3175 4525);
WIRE 16 -1 (-3350 4525)(-3350 4600);
WIRE 16 -1 (-3175 4450)(-3175 4525);
WIRE 16 -1 (-2175 4425)(-2175 4550);
WIRE 16 -1 (-2425 4550)(-2175 4550);
WIRE 16 -1 (-2425 4425)(-2425 4550);
WIRE 16 -1 (-2425 4550)(-2425 4600);
WIRE 16 -1 (-7875 5475)(-8575 5475);
FORCEPROP 2 LAST SIG_NAME SMB_BMC_SWB_EN
J 0
(-8435 5485);
DISPLAY 0.510638 (-8435 5485);
PAINT WHITE (-8435 5485);
WIRE 16 -1 (-6200 4925)(-5200 4925);
WIRE 16 -1 (-5200 4925)(-5200 5375);
WIRE 16 -1 (-5200 5375)(-4800 5375);
WIRE 16 -1 (-5875 5375)(-5200 5375);
FORCEPROP 0 LAST CDS_PHYS_NET_NAME SMB_BMC_SWB_BUF_R_SCL
J 0
(-5860 5423);
PAINT MONO (-5860 5423);
DISPLAY INVISIBLE (-5860 5423);
FORCEPROP 2 LAST SIG_NAME SMB_BMC_SWB_BUF_R_SCL
J 0
(-5810 5385);
DISPLAY 0.510638 (-5810 5385);
PAINT WHITE (-5810 5385);
FORCEPROP 2 LASTPROP $XRERR UNIQUE?
J 0
(-6050 5385);
DISPLAY 0.638298 (-6050 5385);
PAINT MONO (-6050 5385);
DISPLAY INVISIBLE (-6050 5385);
WIRE 16 -1 (-4350 5375)(-4800 5375);
WIRE 16 -1 (-4800 5600)(-4800 5375);
WIRE 16 -1 (-5100 4850)(-5100 5275);
WIRE 16 -1 (-5100 4850)(-6200 4850);
WIRE 16 -1 (-5100 5275)(-4550 5275);
WIRE 16 -1 (-5875 5275)(-5100 5275);
FORCEPROP 0 LAST CDS_PHYS_NET_NAME SMB_BMC_SWB_BUF_R_SDA
J 0
(-5860 5323);
PAINT MONO (-5860 5323);
DISPLAY INVISIBLE (-5860 5323);
FORCEPROP 2 LAST SIG_NAME SMB_BMC_SWB_BUF_R_SDA
J 0
(-5810 5285);
DISPLAY 0.510638 (-5810 5285);
PAINT WHITE (-5810 5285);
FORCEPROP 2 LASTPROP $XRERR UNIQUE?
J 0
(-6050 5285);
DISPLAY 0.638298 (-6050 5285);
PAINT MONO (-6050 5285);
DISPLAY INVISIBLE (-6050 5285);
WIRE 16 -1 (-4350 5275)(-4550 5275);
WIRE 16 -1 (-4550 5600)(-4550 5275);
WIRE 16 -1 (-5650 4100)(-4300 4100);
FORCEPROP 0 LAST CDS_PHYS_NET_NAME SMB_BMC_GPU_EN_R1
J 0
(-5535 4148);
PAINT MONO (-5535 4148);
DISPLAY INVISIBLE (-5535 4148);
FORCEPROP 2 LAST SIG_NAME SMB_BMC_GPU_EN_R1
J 0
(-5235 4110);
DISPLAY 0.510638 (-5235 4110);
PAINT WHITE (-5235 4110);
FORCEPROP 2 LASTPROP $XRERR UNIQUE?
J 0
(-5475 4110);
DISPLAY 0.638298 (-5475 4110);
PAINT MONO (-5475 4110);
DISPLAY INVISIBLE (-5475 4110);
WIRE 16 -1 (-4300 3900)(-4700 3900);
WIRE 16 -1 (-4700 3475)(-4700 3900);
WIRE 16 -1 (-4700 3900)(-5650 3900);
FORCEPROP 0 LAST CDS_PHYS_NET_NAME SMB_1_BMC_GPU_R_SDA
J 0
(-6310 3948);
PAINT MONO (-6310 3948);
DISPLAY INVISIBLE (-6310 3948);
FORCEPROP 2 LAST SIG_NAME SMB_1_BMC_GPU_R_SDA
J 2
(-4785 3910);
DISPLAY 0.510638 (-4785 3910);
PAINT WHITE (-4785 3910);
FORCEPROP 2 LASTPROP $XRERR UNIQUE?
J 0
(-5025 3910);
DISPLAY 0.638298 (-5025 3910);
PAINT MONO (-5025 3910);
DISPLAY INVISIBLE (-5025 3910);
WIRE 16 -1 (-4025 3475)(-4700 3475);
WIRE 16 -1 (-4600 3550)(-4025 3550);
WIRE 16 -1 (-4600 3550)(-4600 4000);
WIRE 16 -1 (-4300 4000)(-4600 4000);
WIRE 16 -1 (-4600 4000)(-5650 4000);
FORCEPROP 0 LAST CDS_PHYS_NET_NAME SMB_1_BMC_GPU_R_SCL
J 0
(-6310 4048);
PAINT MONO (-6310 4048);
DISPLAY INVISIBLE (-6310 4048);
FORCEPROP 2 LAST SIG_NAME SMB_1_BMC_GPU_R_SCL
J 2
(-4785 4010);
DISPLAY 0.510638 (-4785 4010);
PAINT WHITE (-4785 4010);
FORCEPROP 2 LASTPROP $XRERR UNIQUE?
J 0
(-5025 4010);
DISPLAY 0.638298 (-5025 4010);
PAINT MONO (-5025 4010);
DISPLAY INVISIBLE (-5025 4010);
WIRE 16 -1 (-600 4000)(-1775 4000);
FORCEPROP 0 LAST CDS_PHYS_NET_NAME SMB_1_BMC_GPU_BUF_SCL
J 0
(-1660 4048);
PAINT MONO (-1660 4048);
DISPLAY INVISIBLE (-1660 4048);
FORCEPROP 2 LAST SIG_NAME SMB_1_BMC_GPU_BUF_SCL
J 0
(-1210 4010);
DISPLAY 0.510638 (-1210 4010);
PAINT WHITE (-1210 4010);
WIRE 16 -1 (-600 3900)(-1775 3900);
FORCEPROP 0 LAST CDS_PHYS_NET_NAME SMB_1_BMC_GPU_BUF_SDA
J 0
(-1660 3948);
PAINT MONO (-1660 3948);
DISPLAY INVISIBLE (-1660 3948);
FORCEPROP 2 LAST SIG_NAME SMB_1_BMC_GPU_BUF_SDA
J 0
(-1210 3910);
DISPLAY 0.510638 (-1210 3910);
PAINT WHITE (-1210 3910);
WIRE 16 -1 (-2725 3475)(-2725 3900);
WIRE 16 -1 (-2725 3475)(-3825 3475);
WIRE 16 -1 (-2725 3900)(-2175 3900);
WIRE 16 -1 (-2725 3900)(-3500 3900);
FORCEPROP 0 LAST CDS_PHYS_NET_NAME SMB_1_BMC_GPU_BUF_R_SDA
J 0
(-3385 3948);
PAINT MONO (-3385 3948);
DISPLAY INVISIBLE (-3385 3948);
FORCEPROP 2 LAST SIG_NAME SMB_1_BMC_GPU_BUF_R_SDA
J 0
(-3410 3910);
DISPLAY 0.510638 (-3410 3910);
PAINT WHITE (-3410 3910);
FORCEPROP 2 LASTPROP $XRERR UNIQUE?
J 0
(-3650 3910);
DISPLAY 0.638298 (-3650 3910);
PAINT MONO (-3650 3910);
DISPLAY INVISIBLE (-3650 3910);
WIRE 16 -1 (-2175 4225)(-2175 3900);
WIRE 16 -1 (-1975 3900)(-2175 3900);
WIRE 16 -1 (-3825 3550)(-2825 3550);
WIRE 16 -1 (-2825 3550)(-2825 4000);
WIRE 16 -1 (-2425 4000)(-2825 4000);
WIRE 16 -1 (-2825 4000)(-3500 4000);
FORCEPROP 0 LAST CDS_PHYS_NET_NAME SMB_1_BMC_GPU_BUF_R_SCL
J 0
(-3385 4048);
PAINT MONO (-3385 4048);
DISPLAY INVISIBLE (-3385 4048);
FORCEPROP 2 LAST SIG_NAME SMB_1_BMC_GPU_BUF_R_SCL
J 0
(-3410 4010);
DISPLAY 0.510638 (-3410 4010);
PAINT WHITE (-3410 4010);
FORCEPROP 2 LASTPROP $XRERR UNIQUE?
J 0
(-3650 4010);
DISPLAY 0.638298 (-3650 4010);
PAINT MONO (-3650 4010);
DISPLAY INVISIBLE (-3650 4010);
WIRE 16 -1 (-2425 4225)(-2425 4000);
WIRE 16 -1 (-1975 4000)(-2425 4000);
WIRE 16 -1 (-2975 5375)(-4150 5375);
FORCEPROP 0 LAST CDS_PHYS_NET_NAME SMB_BMC_SWB_BUF_SCL
J 0
(-4035 5423);
PAINT MONO (-4035 5423);
DISPLAY INVISIBLE (-4035 5423);
FORCEPROP 2 LAST SIG_NAME SMB_BMC_SWB_BUF_SCL
J 0
(-3585 5385);
DISPLAY 0.510638 (-3585 5385);
PAINT WHITE (-3585 5385);
WIRE 16 -1 (-2975 5275)(-4150 5275);
FORCEPROP 0 LAST CDS_PHYS_NET_NAME SMB_BMC_SWB_BUF_SDA
J 0
(-4035 5323);
PAINT MONO (-4035 5323);
DISPLAY INVISIBLE (-4035 5323);
FORCEPROP 2 LAST SIG_NAME SMB_BMC_SWB_BUF_SDA
J 0
(-3585 5285);
DISPLAY 0.510638 (-3585 5285);
PAINT WHITE (-3585 5285);
WIRE 16 -1 (-3200 2550)(-4375 2550);
FORCEPROP 0 LAST CDS_PHYS_NET_NAME SMB_2_BMC_GPU_BUF_SDA
J 0
(-4260 2598);
PAINT MONO (-4260 2598);
DISPLAY INVISIBLE (-4260 2598);
FORCEPROP 2 LAST SIG_NAME SMB_2_BMC_GPU_BUF_SDA
J 0
(-3810 2560);
DISPLAY 0.510638 (-3810 2560);
PAINT WHITE (-3810 2560);
WIRE 16 -1 (-3200 2650)(-4375 2650);
FORCEPROP 0 LAST CDS_PHYS_NET_NAME SMB_2_BMC_GPU_BUF_SCL
J 0
(-4260 2698);
PAINT MONO (-4260 2698);
DISPLAY INVISIBLE (-4260 2698);
FORCEPROP 2 LAST SIG_NAME SMB_2_BMC_GPU_BUF_SCL
J 0
(-3810 2660);
DISPLAY 0.510638 (-3810 2660);
PAINT WHITE (-3810 2660);
WIRE 16 -1 (-5850 4000)(-6875 4000);
FORCEPROP 0 LAST CDS_PHYS_NET_NAME SMB_1_BMC_GPU_SCL
J 0
(-6760 4048);
PAINT MONO (-6760 4048);
DISPLAY INVISIBLE (-6760 4048);
FORCEPROP 2 LAST SIG_NAME SMB_1_BMC_GPU_SCL
J 2
(-6085 4010);
DISPLAY 0.510638 (-6085 4010);
PAINT WHITE (-6085 4010);
WIRE 16 -1 (-7725 2750)(-6900 2750);
FORCEPROP 0 LAST CDS_PHYS_NET_NAME SMB_BMC_GPU_EN_R3
J 0
(-7660 2798);
PAINT MONO (-7660 2798);
DISPLAY INVISIBLE (-7660 2798);
FORCEPROP 2 LAST SIG_NAME SMB_BMC_GPU_EN_R3
J 0
(-7435 2760);
DISPLAY 0.510638 (-7435 2760);
PAINT WHITE (-7435 2760);
FORCEPROP 2 LASTPROP $XRERR UNIQUE?
J 0
(-7675 2760);
DISPLAY 0.638298 (-7675 2760);
PAINT MONO (-7675 2760);
DISPLAY INVISIBLE (-7675 2760);
WIRE 16 -1 (-7925 2750)(-8650 2750);
FORCEPROP 2 LAST SIG_NAME SMB_BMC_GPU_EN
J 0
(-8510 2760);
DISPLAY 0.510638 (-8510 2760);
PAINT WHITE (-8510 2760);
WIRE 16 -1 (-7925 2650)(-8650 2650);
FORCEPROP 0 LAST CDS_PHYS_NET_NAME SMB_2_BMC_GPU_SCL
J 0
(-8535 2698);
PAINT MONO (-8535 2698);
DISPLAY INVISIBLE (-8535 2698);
FORCEPROP 2 LAST SIG_NAME SMB_2_BMC_GPU_SCL
J 2
(-8110 2660);
DISPLAY 0.510638 (-8110 2660);
PAINT WHITE (-8110 2660);
WIRE 16 -1 (-7875 5375)(-8575 5375);
FORCEPROP 0 LAST CDS_PHYS_NET_NAME SMB_BMC_SWB_SCL
J 0
(-8460 5423);
PAINT MONO (-8460 5423);
DISPLAY INVISIBLE (-8460 5423);
FORCEPROP 2 LAST SIG_NAME SMB_BMC_SWB_SCL
J 2
(-8110 5385);
DISPLAY 0.510638 (-8110 5385);
PAINT WHITE (-8110 5385);
WIRE 16 -1 (-7875 5275)(-8575 5275);
FORCEPROP 0 LAST CDS_PHYS_NET_NAME SMB_BMC_SWB_SDA
J 0
(-8460 5323);
PAINT MONO (-8460 5323);
DISPLAY INVISIBLE (-8460 5323);
FORCEPROP 2 LAST SIG_NAME SMB_BMC_SWB_SDA
J 2
(-8110 5285);
DISPLAY 0.510638 (-8110 5285);
PAINT WHITE (-8110 5285);
WIRE 16 -1 (-7925 2550)(-8650 2550);
FORCEPROP 0 LAST CDS_PHYS_NET_NAME SMB_2_BMC_GPU_SDA
J 0
(-8535 2598);
PAINT MONO (-8535 2598);
DISPLAY INVISIBLE (-8535 2598);
FORCEPROP 2 LAST SIG_NAME SMB_2_BMC_GPU_SDA
J 2
(-8110 2560);
DISPLAY 0.510638 (-8110 2560);
PAINT WHITE (-8110 2560);
DOT 1 (-5325 2550);
DOT 1 (-6975 5375);
CIRCLE (-6525 1450)(-6365 1450);
PAINT YELLOW (-6525 1450);
DOT 1 (-2425 4550);
DOT 1 (-3350 4525);
DOT 1 (-2175 3900);
DOT 1 (-2425 4000);
DOT 1 (-2725 3900);
DOT 1 (-2825 4000);
DOT 1 (-2350 1825);
DOT 1 (-2100 1225);
DOT 1 (-2350 1125);
DOT 1 (-2550 1125);
DOT 1 (-3375 1800);
DOT 1 (-4550 5275);
DOT 1 (-4800 5925);
DOT 1 (-4800 5375);
DOT 1 (-5200 5375);
DOT 1 (-5100 5275);
DOT 1 (-5825 5900);
DOT 1 (-7075 5275);
DOT 1 (-6700 4100);
DOT 1 (-4600 4000);
DOT 1 (-4700 3900);
DOT 1 (-5025 3200);
DOT 1 (-4775 2550);
DOT 1 (-5025 2650);
DOT 1 (-5950 3175);
DOT 1 (-5425 2650);
DOT 1 (-4650 1225);
DOT 1 (-7300 2550);
DOT 1 (-7200 2650);
DOT 1 (-6475 1325);
CIRCLE (-8525 5650)(-8365 5650);
PAINT YELLOW (-8525 5650);
CIRCLE (-8500 2875)(-8340 2875);
PAINT YELLOW (-8500 2875);
DOT 1 (-2425 1225);
DOT 1 (-4525 1125);
FORCENOTE
TBC
(-8575 5600) 0;
DISPLAY LEFT (-8575 5600);
DISPLAY 1.021277 (-8575 5600);
FORCENOTE
TBC
(-8550 2825) 0;
DISPLAY LEFT (-8550 2825);
DISPLAY 1.021277 (-8550 2825);
FORCENOTE
TBC
(-6575 1400) 0;
DISPLAY LEFT (-6575 1400);
DISPLAY 1.021277 (-6575 1400);
FORCENOTE
I3C FROM BMC
(-5675 900) 0;
DISPLAY LEFT (-5675 900);
DISPLAY 1.595745 (-5675 900);
PAINT WHITE (-5675 900);
QUIT
